# Altium SchDoc records: USER_IO.SchDoc
|HEADER=Protel for Windows - Schematic Capture Binary File Version 5.0|Weight=1616|MinorVersion=4
|RECORD=31|FontIdCount=7|Size1=10|FontName1=Times New Roman|Size2=8|FontName2=Arial|Size3=10|FontName3=Arial|Size4=12|Underline4=T|FontName4=Arial|Size5=24|FontName5=Times New Roman|Size6=10|Underline6=T|FontName6=Times New Roman|Size7=11|FontName7=Arial|UseMBCS=T|IsBOC=T|HotSpotGridOn=T|HotSpotGridSize_Frac=40000|SheetStyle=12|SystemFont=3|BorderOn=T|SheetNumberSpaceSize=12|AreaColor=16317695|SnapGridOn=T|SnapGridSize=1|VisibleGridOn=T|VisibleGridSize=10|CustomX=2338|CustomX_Frac=58268|CustomY=1653|CustomY_Frac=54331|CustomXZones=8|CustomYZones=6|CustomMarginWidth=19|CustomMarginWidth_Frac=80000|ShowTemplateGraphics=T|TemplateFileName=C:\Users\<user>\Documents\Altium\AD20\Templates\Timecard.SchDot|Display_Unit=0
|RECORD=39|IsNotAccesible=T|OwnerPartId=-1|FileName=C:\Users\<user>\Documents\Altium\AD20\Templates\Timecard.SchDot
|RECORD=4|OwnerIndex=1|OwnerPartId=-1|Location.X=1594|Location.Y=39|Color=8388608|FontID=4|Text=timingcard.com|URL=http://timingcard.com
|RECORD=6|OwnerIndex=1|IndexInSheet=1|OwnerPartId=-1|LocationCount=2|X1=1680|Y1=35|X2=1576|Y2=35
|RECORD=4|OwnerIndex=1|IndexInSheet=2|OwnerPartId=-1|Location.X=1615|Location.Y=27|Justification=4|Color=16711680|FontID=7|Text==SheetNumber
|RECORD=4|OwnerIndex=1|IndexInSheet=3|OwnerPartId=-1|Location.X=1581|Location.X_Frac=42446|Location.Y=29|Location.Y_Frac=96838|Justification=3|FontID=2|Text=SHEET
|RECORD=4|OwnerIndex=1|IndexInSheet=4|OwnerPartId=-1|Location.X=1639|Location.X_Frac=42446|Location.Y=29|Location.Y_Frac=96838|Justification=3|FontID=2|Text=OF
|RECORD=6|OwnerIndex=1|IndexInSheet=5|OwnerPartId=-1|LineWidth=1|LocationCount=2|X1=1679|X1_Frac=42446|Y1=117|Y1_Frac=96838|X2=1576|Y2=118
|RECORD=4|OwnerIndex=1|IndexInSheet=6|OwnerPartId=-1|Location.X=1659|Location.Y=27|Justification=4|Color=16711680|FontID=7|Text==SheetTotal
|RECORD=30|OwnerIndex=1|IndexInSheet=7|OwnerPartId=-1|Location.X=1578|Location.Y=65|Corner.X=1673|Corner.X_Frac=88801|Corner.Y=115|KeepAspect=T|FileName=C:\Users\<user>\Desktop\Timecard Logo\TIMECARD.jpg
|RECORD=6|OwnerIndex=1|IndexInSheet=8|OwnerPartId=-1|LineWidth=1|LocationCount=2|X1=1576|X1_Frac=3162|Y1=117|Y1_Frac=42446|X2=1576|Y2=21
|RECORD=6|OwnerIndex=1|IndexInSheet=9|OwnerPartId=-1|LocationCount=2|X1=1680|Y1=51|X2=1576|Y2=51
|RECORD=4|OwnerIndex=1|IndexInSheet=10|OwnerPartId=-1|Location.X=1581|Location.X_Frac=42446|Location.Y=56|Location.Y_Frac=96838|Justification=3|FontID=2|Text=REV
|RECORD=4|OwnerIndex=1|IndexInSheet=11|OwnerPartId=-1|Location.X=1619|Location.Y=57|Justification=3|FontID=2|Text=DATE
|RECORD=6|OwnerIndex=1|IndexInSheet=12|OwnerPartId=-1|LocationCount=2|X1=1680|Y1=65|X2=1576|Y2=65
|RECORD=4|OwnerIndex=1|IndexInSheet=13|OwnerPartId=-1|Location.X=1605|Location.Y=58|Justification=4|Color=16711680|FontID=7|Text==ProjectRevision
|RECORD=4|OwnerIndex=1|IndexInSheet=14|OwnerPartId=-1|Location.X=1659|Location.Y=58|Justification=4|Color=16711680|FontID=7|Text==ProjectDate
|RECORD=41|IndexInSheet=1|OwnerPartId=-1|Color=8388608|FontID=1|IsHidden=T|Text=*|Name=CurrentTime|ReadOnlyState=1
|RECORD=41|IndexInSheet=2|OwnerPartId=-1|Color=8388608|FontID=1|IsHidden=T|Text=*|Name=CurrentDate|ReadOnlyState=1
|RECORD=41|IndexInSheet=3|OwnerPartId=-1|Color=8388608|FontID=1|IsHidden=T|Text=*|Name=Time|ReadOnlyState=1
|RECORD=41|IndexInSheet=4|OwnerPartId=-1|Color=8388608|FontID=1|IsHidden=T|Text=*|Name=Date|ReadOnlyState=1
|RECORD=41|IndexInSheet=5|OwnerPartId=-1|Color=8388608|FontID=1|IsHidden=T|Text=*|Name=DocumentFullPathAndName|ReadOnlyState=1
|RECORD=41|IndexInSheet=6|OwnerPartId=-1|Color=8388608|FontID=1|IsHidden=T|Text=*|Name=DocumentName|ReadOnlyState=1
|RECORD=41|IndexInSheet=7|OwnerPartId=-1|Color=8388608|FontID=1|IsHidden=T|Text=*|Name=ModifiedDate|ReadOnlyState=1
|RECORD=41|IndexInSheet=8|OwnerPartId=-1|Color=8388608|FontID=1|IsHidden=T|Text=*|Name=ApprovedBy|ReadOnlyState=1
|RECORD=41|IndexInSheet=9|OwnerPartId=-1|Color=8388608|FontID=1|IsHidden=T|Text=*|Name=CheckedBy|ReadOnlyState=1
|RECORD=41|IndexInSheet=10|OwnerPartId=-1|Color=8388608|FontID=1|IsHidden=T|Text=*|Name=Author|ReadOnlyState=1
|RECORD=41|IndexInSheet=11|OwnerPartId=-1|Color=8388608|FontID=1|IsHidden=T|Text=*|Name=CompanyName|ReadOnlyState=1
|RECORD=41|IndexInSheet=12|OwnerPartId=-1|Color=8388608|FontID=1|IsHidden=T|Text=*|Name=DrawnBy|ReadOnlyState=1
|RECORD=41|IndexInSheet=13|OwnerPartId=-1|Color=8388608|FontID=1|IsHidden=T|Text=*|Name=Engineer|ReadOnlyState=1
|RECORD=41|IndexInSheet=14|OwnerPartId=-1|Color=8388608|FontID=1|IsHidden=T|Text=*|Name=Organization|ReadOnlyState=1
|RECORD=41|IndexInSheet=15|OwnerPartId=-1|Color=8388608|FontID=1|IsHidden=T|Text=*|Name=Address1|ReadOnlyState=1
|RECORD=41|IndexInSheet=16|OwnerPartId=-1|Color=8388608|FontID=1|IsHidden=T|Text=*|Name=Address2|ReadOnlyState=1
|RECORD=41|IndexInSheet=17|OwnerPartId=-1|Color=8388608|FontID=1|IsHidden=T|Text=*|Name=Address3|ReadOnlyState=1
|RECORD=41|IndexInSheet=18|OwnerPartId=-1|Color=8388608|FontID=1|IsHidden=T|Text=*|Name=Address4|ReadOnlyState=1
|RECORD=41|IndexInSheet=19|OwnerPartId=-1|Color=8388608|FontID=1|IsHidden=T|Text=*|Name=Title|ReadOnlyState=1
|RECORD=41|IndexInSheet=20|OwnerPartId=-1|Color=8388608|FontID=1|IsHidden=T|Text=1|Name=DocumentNumber|ReadOnlyState=1
|RECORD=41|IndexInSheet=21|OwnerPartId=-1|Color=8388608|FontID=1|IsHidden=T|Text=*|Name=Revision|ReadOnlyState=1
|RECORD=41|IndexInSheet=22|OwnerPartId=-1|Color=8388608|FontID=1|IsHidden=T|Text=1|Name=SheetNumber|ReadOnlyState=1
|RECORD=41|IndexInSheet=23|OwnerPartId=-1|Color=8388608|FontID=1|IsHidden=T|Text=7|Name=SheetTotal|ReadOnlyState=1
|RECORD=41|IndexInSheet=24|OwnerPartId=-1|Color=8388608|FontID=1|IsHidden=T|Text=*|Name=Rule|ReadOnlyState=1
|RECORD=41|IndexInSheet=25|OwnerPartId=-1|Color=8388608|FontID=1|IsHidden=T|Text=*|Name=ImagePath|ReadOnlyState=1
|RECORD=41|IndexInSheet=26|OwnerPartId=-1|Color=8388608|FontID=1|IsHidden=T|Text=*|Name=ProjectName|ReadOnlyState=1
|RECORD=41|IndexInSheet=27|OwnerPartId=-1|Color=8388608|FontID=1|IsHidden=T|Text=*|Name=Application_BuildNumber|ReadOnlyState=1
|RECORD=41|IndexInSheet=28|OwnerPartId=-1|Color=8388608|FontID=1|IsHidden=T|Name=ConfigurationParameters|ReadOnlyState=1
|RECORD=41|IndexInSheet=29|OwnerPartId=-1|Color=8388608|FontID=1|IsHidden=T|Name=ConfiguratorName|ReadOnlyState=1
|RECORD=41|IndexInSheet=30|OwnerPartId=-1|Color=8388608|FontID=1|IsHidden=T|Name=VersionControl_RevNumber|ReadOnlyState=1
|RECORD=41|IndexInSheet=31|OwnerPartId=-1|Color=8388608|FontID=1|IsHidden=T|Name=IsUserConfigurable|ReadOnlyState=1
|RECORD=41|IndexInSheet=32|OwnerPartId=-1|Color=8388608|FontID=1|IsHidden=T|Name=VersionControl_ProjFolderRevNumber|ReadOnlyState=1
|RECORD=41|IndexInSheet=33|OwnerPartId=-1|Color=8388608|FontID=1|IsHidden=T|Name=SPICEModelCache|ReadOnlyState=1
|RECORD=1|LibReference=NC7WV125K8X|ComponentDescription=Integrated Circuit|PartCount=2|DisplayModeCount=1|IndexInSheet=34|OwnerPartId=-1|Location.X=400|Location.Y=685|CurrentPartId=1|LibraryPath=*|SourceLibraryName=SamacSys.SchLib|TargetFileName=*|AreaColor=11599871|Color=128|PartIDLocked=T|DesignItemId=NC7WV125K8X|AllPinCount=8
|RECORD=41|OwnerIndex=50|OwnerPartId=-1|Location.X=400|Location.Y=685|Color=8388608|FontID=6|IsHidden=T|Text=https://www.mouser.com/datasheet/2/308/NC7WV125-1301459.pdf|Name=Datasheet Link
|RECORD=41|OwnerIndex=50|IndexInSheet=1|OwnerPartId=-1|Location.X=400|Location.Y=685|Color=8388608|FontID=1|IsHidden=T|Text=0.9mm|Name=Height
|RECORD=41|OwnerIndex=50|IndexInSheet=2|OwnerPartId=-1|Location.X=400|Location.Y=685|Color=8388608|FontID=1|IsHidden=T|Text=ON Semiconductor|Name=Manufacturer_Name
|RECORD=41|OwnerIndex=50|IndexInSheet=3|OwnerPartId=-1|Location.X=400|Location.Y=685|Color=8388608|FontID=1|IsHidden=T|Text=NC7WV125K8X|Name=Manufacturer_Part_Number
|RECORD=41|OwnerIndex=50|IndexInSheet=4|OwnerPartId=-1|Location.X=400|Location.Y=685|Color=8388608|FontID=1|IsHidden=T|Text=512-NC7WV125K8X|Name=Mouser Part Number
|RECORD=41|OwnerIndex=50|IndexInSheet=5|OwnerPartId=-1|Location.X=400|Location.Y=685|Color=8388608|FontID=6|IsHidden=T|Text=https://www.mouser.com/Search/Refine.aspx?Keyword=512-NC7WV125K8X|Name=Mouser Price/Stock
|RECORD=41|OwnerIndex=50|IndexInSheet=6|OwnerPartId=-1|Location.X=400|Location.Y=685|Color=8388608|FontID=1|IsHidden=T|Text=NC7WV125K8X|Name=Arrow Part Number
|RECORD=41|OwnerIndex=50|IndexInSheet=7|OwnerPartId=-1|Location.X=400|Location.Y=685|Color=8388608|FontID=6|IsHidden=T|Text=https://www.arrow.com/en/products/nc7wv125k8x/on-semiconductor|Name=Arrow Price/Stock
|RECORD=14|OwnerIndex=50|IsNotAccesible=T|IndexInSheet=8|OwnerPartId=1|Location.X=420|Location.Y=660|Corner.X=490|Corner.Y=785|LineWidth=1|Color=128|AreaColor=11599871|IsSolid=T
|RECORD=2|OwnerIndex=50|OwnerPartId=1|FormalType=1|Electrical=4|PinConglomerate=58|PinLength=20|Location.X=420|Location.Y=775|Designator=1|SwapIDPart=Ž&Ž||PinPropagationDelay=0.000000E+000
|RECORD=2|OwnerIndex=50|OwnerPartId=1|FormalType=1|Electrical=4|PinConglomerate=58|PinLength=20|Location.X=420|Location.Y=750|Designator=2|SwapIDPart=Ž&Ž||PinPropagationDelay=0.000000E+000
|RECORD=2|OwnerIndex=50|OwnerPartId=1|FormalType=1|Electrical=4|PinConglomerate=58|PinLength=20|Location.X=420|Location.Y=695|Designator=3|SwapIDPart=Ž&Ž||PinPropagationDelay=0.000000E+000
|RECORD=2|OwnerIndex=50|OwnerPartId=1|FormalType=1|Electrical=4|PinConglomerate=58|PinLength=20|Location.X=420|Location.Y=665|Name=GND|Designator=4|SwapIDPart=Ž&Ž||PinPropagationDelay=0.000000E+000
|RECORD=2|OwnerIndex=50|OwnerPartId=1|FormalType=1|Electrical=4|PinConglomerate=58|PinLength=20|Location.X=420|Location.Y=675|Name=VCC|Designator=8|SwapIDPart=Ž&Ž||PinPropagationDelay=0.000000E+000
|RECORD=2|OwnerIndex=50|OwnerPartId=1|FormalType=1|Electrical=4|PinConglomerate=58|PinLength=20|Location.X=420|Location.Y=720|Designator=7|SwapIDPart=Ž&Ž||PinPropagationDelay=0.000000E+000
|RECORD=2|OwnerIndex=50|OwnerPartId=1|FormalType=1|Electrical=4|PinConglomerate=56|PinLength=20|Location.X=490|Location.Y=750|Designator=6|SwapIDPart=Ž&Ž||PinPropagationDelay=0.000000E+000
|RECORD=2|OwnerIndex=50|OwnerPartId=1|FormalType=1|Electrical=4|PinConglomerate=56|PinLength=20|Location.X=490|Location.Y=695|Designator=5|SwapIDPart=Ž&Ž||PinPropagationDelay=0.000000E+000
|RECORD=6|OwnerIndex=50|IsNotAccesible=T|IndexInSheet=17|OwnerPartId=1|LineWidth=1|Color=16711680|LocationCount=4|X1=445|Y1=760|X2=445|Y2=740|X3=465|Y3=750|X4=445|Y4=760
|RECORD=12|OwnerIndex=50|IsNotAccesible=T|IndexInSheet=18|OwnerPartId=1|Location.X=455|Location.Y=757|Radius=1|Radius_Frac=79777|LineWidth=1|EndAngle=360.000|Color=16711680
|RECORD=6|OwnerIndex=50|IsNotAccesible=T|IndexInSheet=19|OwnerPartId=1|LineWidth=1|Color=16711680|LocationCount=4|X1=465|Y1=705|X2=465|Y2=685|X3=445|Y3=695|X4=465|Y4=705
|RECORD=12|OwnerIndex=50|IsNotAccesible=T|IndexInSheet=20|OwnerPartId=1|Location.X=455|Location.Y=702|Radius=1|Radius_Frac=79777|LineWidth=1|EndAngle=360.000|Color=16711680
|RECORD=6|OwnerIndex=50|IsNotAccesible=T|IndexInSheet=21|OwnerPartId=1|LineWidth=1|Color=16711680|LocationCount=3|X1=455|Y1=704|X2=455|Y2=720|X3=420|Y3=720
|RECORD=6|OwnerIndex=50|IsNotAccesible=T|IndexInSheet=22|OwnerPartId=1|LineWidth=1|Color=16711680|LocationCount=3|X1=455|Y1=759|X2=455|Y2=775|X3=420|Y3=775
|RECORD=6|OwnerIndex=50|IsNotAccesible=T|IndexInSheet=23|OwnerPartId=1|LineWidth=1|Color=16711680|LocationCount=2|X1=420|Y1=750|X2=445|Y2=750
|RECORD=6|OwnerIndex=50|IsNotAccesible=T|IndexInSheet=24|OwnerPartId=1|LineWidth=1|Color=16711680|LocationCount=2|X1=465|Y1=750|X2=490|Y2=750
|RECORD=6|OwnerIndex=50|IsNotAccesible=T|IndexInSheet=25|OwnerPartId=1|LineWidth=1|Color=16711680|LocationCount=2|X1=465|Y1=695|X2=490|Y2=695
|RECORD=6|OwnerIndex=50|IsNotAccesible=T|IndexInSheet=26|OwnerPartId=1|LineWidth=1|Color=16711680|LocationCount=2|X1=445|Y1=695|X2=420|Y2=695
|RECORD=34|OwnerIndex=50|IndexInSheet=-1|OwnerPartId=-1|Location.X=419|Location.Y=785|Color=8388608|FontID=1|Text=U8|Name=Designator|ReadOnlyState=1
|RECORD=41|OwnerIndex=50|IndexInSheet=-1|OwnerPartId=-1|Location.X=419|Location.Y=650|Color=8388608|FontID=1|Text=NC7WV125K8X|Name=Comment
|RECORD=44|OwnerIndex=50
|RECORD=45|OwnerIndex=88|IndexInSheet=-1|ModelName=SOP50P310X90-8N|ModelType=PCBLIB|DatafileCount=1|ModelDatafile0=C:\Users\<user>\Documents\AltiumLL\SamacSys.PcbLib|ModelDatafileEntity0=SOP50P310X90-8N|ModelDatafileKind0=PCBLIB|IsCurrent=T
|RECORD=46|OwnerIndex=89
|RECORD=48|OwnerIndex=89
|RECORD=17|IndexInSheet=35|OwnerPartId=-1|Style=4|ShowNetName=T|Location.X=710|Location.Y=620|Orientation=3|Color=128|FontID=1|Text=GND
|RECORD=1|LibReference=CN-1P-M-RF3|ComponentDescription=Ultra Miniature Coaxial Connector Jack, 60 V, 50 Ohm, -40 to 90 degC, RoHS, Tape and Reel|PartCount=2|DisplayModeCount=1|IndexInSheet=36|OwnerPartId=-1|Location.X=640|Location.Y=770|CurrentPartId=1|LibraryPath=*|SourceLibraryName=Altium Content Vault|TargetFileName=*|AreaColor=11599871|Color=128|PartIDLocked=T|DesignItemId=CMP-2000-07505-1|AllPinCount=3
|RECORD=8|OwnerIndex=93|IsNotAccesible=T|OwnerPartId=1|Location.X=660|Location.Y=750|Radius=20|SecondaryRadius=20|LineWidth=1|Color=16711680|AreaColor=16777215
|RECORD=8|OwnerIndex=93|IsNotAccesible=T|IndexInSheet=1|OwnerPartId=1|Location.X=660|Location.Y=750|Radius=4|SecondaryRadius=4|LineWidth=1|Color=16711680|AreaColor=16777215
|RECORD=2|OwnerIndex=93|OwnerPartId=1|FormalType=1|Electrical=4|PinConglomerate=51|PinLength=10|Location.X=650|Location.Y=730|Name=1|Designator=1|PinPropagationDelay=0.000000E+000
|RECORD=2|OwnerIndex=93|OwnerPartId=1|FormalType=1|Electrical=4|PinConglomerate=50|PinLength=10|Location.X=640|Location.Y=750|Name=2|Designator=2|PinPropagationDelay=0.000000E+000
|RECORD=2|OwnerIndex=93|OwnerPartId=1|FormalType=1|Electrical=4|PinConglomerate=51|PinLength=10|Location.X=670|Location.Y=730|Name=3|Designator=3|PinPropagationDelay=0.000000E+000
|RECORD=6|OwnerIndex=93|IsNotAccesible=T|IndexInSheet=5|OwnerPartId=1|LineWidth=1|Color=16711680|LocationCount=5|X1=640|Y1=730|X2=640|Y2=770|X3=680|Y3=770|X4=680|Y4=730|X5=640|Y5=730
|RECORD=6|OwnerIndex=93|IsNotAccesible=T|IndexInSheet=6|OwnerPartId=1|LineWidth=1|Color=16711680|LocationCount=2|X1=640|Y1=750|X2=656|Y2=750
|RECORD=41|OwnerIndex=93|IndexInSheet=7|OwnerPartId=-1|Location.X=628|Location.Y=771|Color=8388608|FontID=1|IsHidden=T|Text=Straight|Name=Orientation
|RECORD=41|OwnerIndex=93|IndexInSheet=8|OwnerPartId=-1|Location.X=628|Location.Y=771|Color=8388608|FontID=1|IsHidden=T|Text=Female|Name=Gender
|RECORD=41|OwnerIndex=93|IndexInSheet=9|OwnerPartId=-1|Location.X=628|Location.Y=771|Color=8388608|FontID=1|IsHidden=T|Text=Vertical|Name=PCB Mounting Orientation
|RECORD=41|OwnerIndex=93|IndexInSheet=10|OwnerPartId=-1|Location.X=628|Location.Y=771|Color=8388608|FontID=1|IsHidden=T|Text=SurfaceMount|Name=Mount
|RECORD=41|OwnerIndex=93|IndexInSheet=11|OwnerPartId=-1|Location.X=628|Location.Y=771|Color=8388608|FontID=1|IsHidden=T|Text=3mm|Name=Length
|RECORD=41|OwnerIndex=93|IndexInSheet=12|OwnerPartId=-1|Location.X=628|Location.Y=771|Color=8388608|FontID=1|IsHidden=T|Text=TapeandReel|Name=Packaging
|RECORD=41|OwnerIndex=93|IndexInSheet=13|OwnerPartId=-1|Location.X=628|Location.Y=771|Color=8388608|FontID=1|IsHidden=T|Text=Jack|Name=Connector Type
|RECORD=41|OwnerIndex=93|IndexInSheet=14|OwnerPartId=-1|Location.X=628|Location.Y=771|Color=8388608|FontID=1|IsHidden=T|Text=LeadFree|Name=Lead Free
|RECORD=41|OwnerIndex=93|IndexInSheet=15|OwnerPartId=-1|Location.X=628|Location.Y=771|Color=8388608|FontID=1|IsHidden=T|Text=1|Name=Package Quantity
|RECORD=41|OwnerIndex=93|IndexInSheet=16|OwnerPartId=-1|Location.X=628|Location.Y=771|Color=8388608|FontID=1|IsHidden=T|Text=SMD/SMT|Name=Termination
|RECORD=41|OwnerIndex=93|IndexInSheet=17|OwnerPartId=-1|Location.X=628|Location.Y=771|Color=8388608|FontID=1|IsHidden=T|Text=CopperAlloy|Name=Contact Material
|RECORD=41|OwnerIndex=93|IndexInSheet=18|OwnerPartId=-1|Location.X=628|Location.Y=771|Color=8388608|FontID=1|IsHidden=T|Text=Pull|Name=Fastening Type
|RECORD=41|OwnerIndex=93|IndexInSheet=19|OwnerPartId=-1|Location.X=628|Location.Y=771|Color=8388608|FontID=1|IsHidden=T|Text=true|Name=RoHSCompliant
|RECORD=41|OwnerIndex=93|IndexInSheet=20|OwnerPartId=-1|Location.X=628|Location.Y=771|Color=8388608|FontID=1|IsHidden=T|Text=LiquidCrystalPolymer|Name=Body Material
|RECORD=41|OwnerIndex=93|IndexInSheet=21|OwnerPartId=-1|Location.X=628|Location.Y=771|Color=8388608|FontID=1|IsHidden=T|Text=SMD/SMT|Name=Case\/Package
|RECORD=41|OwnerIndex=93|IndexInSheet=22|OwnerPartId=-1|Location.X=628|Location.Y=771|Color=8388608|FontID=1|IsHidden=T|Text=90degC|Name=Max Operating Temperature
|RECORD=41|OwnerIndex=93|IndexInSheet=23|OwnerPartId=-1|Location.X=628|Location.Y=771|Color=8388608|FontID=1|IsHidden=T|Text=50Ohm|Name=Impedance
|RECORD=41|OwnerIndex=93|IndexInSheet=24|OwnerPartId=-1|Location.X=628|Location.Y=771|Color=8388608|FontID=6|IsHidden=T|Text=http://www.te.com/commerce/DocumentDelivery/DDEController?Action=srchrtrv&DocNm=1909763&DocType=Customer+Drawing&DocLang=English|Name=Datasheet URL
|RECORD=41|OwnerIndex=93|IndexInSheet=25|OwnerPartId=-1|Location.X=628|Location.Y=771|Color=8388608|FontID=1|IsHidden=T|Text=Gold|Name=Contact Plating
|RECORD=41|OwnerIndex=93|IndexInSheet=26|OwnerPartId=-1|Location.X=628|Location.Y=771|Color=8388608|FontID=1|IsHidden=T|Text=SurfaceMount|Name=Mounting Technology
|RECORD=41|OwnerIndex=93|IndexInSheet=27|OwnerPartId=-1|Location.X=628|Location.Y=771|Color=8388608|FontID=1|IsHidden=T|Text=6GHz|Name=Max Frequency
|RECORD=41|OwnerIndex=93|IndexInSheet=28|OwnerPartId=-1|Location.X=628|Location.Y=771|Color=8388608|FontID=1|IsHidden=T|Text=TECO-1909763-1|Name=Package Reference
|RECORD=41|OwnerIndex=93|IndexInSheet=29|OwnerPartId=-1|Location.X=628|Location.Y=771|Color=8388608|FontID=1|IsHidden=T|Text=Thermoplastic|Name=Insulation Material
|RECORD=41|OwnerIndex=93|IndexInSheet=30|OwnerPartId=-1|Location.X=628|Location.Y=771|Color=8388608|FontID=1|IsHidden=T|Text=-40degC|Name=Min Operating Temperature
|RECORD=41|OwnerIndex=93|IndexInSheet=31|OwnerPartId=-1|Location.X=628|Location.Y=771|Color=8388608|FontID=6|IsHidden=T|Text=http://www.te.com/|Name=Manufacturer URL
|RECORD=41|OwnerIndex=93|IndexInSheet=32|OwnerPartId=-1|Location.X=628|Location.Y=771|Color=8388608|FontID=1|IsHidden=T|Text=Gold|Name=Body Plating
|RECORD=41|OwnerIndex=93|IndexInSheet=33|OwnerPartId=-1|Location.X=628|Location.Y=771|Color=8388608|FontID=1|IsHidden=T|Text=Polymer|Name=Dielectric Material
|RECORD=41|OwnerIndex=93|IndexInSheet=34|OwnerPartId=-1|Location.X=628|Location.Y=771|Color=8388608|FontID=1|IsHidden=T|Text=TE Connectivity|Name=Manufacturer
|RECORD=41|OwnerIndex=93|IndexInSheet=35|OwnerPartId=-1|Location.X=628|Location.Y=771|Color=8388608|FontID=1|IsHidden=T|Text=Compliant|Name=ELV
|RECORD=41|OwnerIndex=93|IndexInSheet=36|OwnerPartId=-1|Location.X=628|Location.Y=771|Color=8388608|FontID=1|IsHidden=T|Text=Rev. B2, 11/2015|Name=Datasheet Version
|RECORD=41|OwnerIndex=93|IndexInSheet=37|OwnerPartId=-1|Location.X=628|Location.Y=771|Color=8388608|FontID=1|IsHidden=T|Text=No|Name=Radiation Hardening
|RECORD=41|OwnerIndex=93|IndexInSheet=38|OwnerPartId=-1|Location.X=628|Location.Y=771|Color=8388608|FontID=1|IsHidden=T|Text=3-Pin Surface Mount Device, Body 2.6 x 2.6 mm|Name=Package Description
|RECORD=41|OwnerIndex=93|IndexInSheet=39|OwnerPartId=-1|Location.X=628|Location.Y=771|Color=8388608|FontID=1|IsHidden=T|Text=Beige|Name=Housing Colour
|RECORD=34|OwnerIndex=93|IndexInSheet=-1|OwnerPartId=-1|Location.X=639|Location.Y=771|Color=8388608|FontID=1|Text=J1|Name=Designator|ReadOnlyState=1
|RECORD=41|OwnerIndex=93|IndexInSheet=-1|OwnerPartId=-1|Location.X=690|Location.Y=730|Color=8388608|FontID=1|Text=1909763-1|Name=Comment
|RECORD=44|OwnerIndex=93
|RECORD=45|OwnerIndex=139|IndexInSheet=-1|Description=SMD, 3-Leads, Body 2.6x2.6mm, Height 1.25mm|UseComponentLibrary=T|ModelName=TECO-1909763-1_V|ModelType=PCBLIB|DatafileCount=1|ModelDatafileEntity0=TECO-1909763-1_V|ModelDatafileKind0=PCBLib|IsCurrent=T|DatalinksLocked=T|DatabaseDatalinksLocked=T
|RECORD=46|OwnerIndex=140
|RECORD=48|OwnerIndex=140
|RECORD=41|OwnerIndex=142|IndexInSheet=-1|OwnerPartId=-1|Color=8388608|FontID=1|Text=2D|Name=Available Preview Images
|RECORD=1|LibReference=CN-S-4F-RF5|ComponentDescription=Coaxial connector, 50 Ohm, -65 to 165 degC, 5-Pin THD, RoHS, Bulk|PartCount=2|DisplayModeCount=1|IndexInSheet=37|OwnerPartId=-1|Location.X=640|Location.Y=690|CurrentPartId=1|LibraryPath=*|SourceLibraryName=Altium Content Vault|TargetFileName=*|AreaColor=11599871|Color=128|PartIDLocked=T|DesignItemId=CMP-2000-05705-1|AllPinCount=5
|RECORD=2|OwnerIndex=144|OwnerPartId=1|FormalType=1|Electrical=4|PinConglomerate=51|PinLength=10|Location.X=680|Location.Y=650|Name=5|Designator=5|SwapIDPart=Ž&Ž1|PinPropagationDelay=0.000000E+000
|RECORD=8|OwnerIndex=144|IsNotAccesible=T|IndexInSheet=1|OwnerPartId=1|Location.X=660|Location.Y=670|Radius=20|SecondaryRadius=20|LineWidth=1|Color=16711680|AreaColor=16777215
|RECORD=8|OwnerIndex=144|IsNotAccesible=T|IndexInSheet=2|OwnerPartId=1|Location.X=660|Location.Y=670|Radius=4|SecondaryRadius=4|LineWidth=1|Color=16711680|AreaColor=16777215
|RECORD=2|OwnerIndex=144|OwnerPartId=1|FormalType=1|Electrical=4|PinConglomerate=50|PinLength=10|Location.X=640|Location.Y=670|Name=1|Designator=1|PinPropagationDelay=0.000000E+000
|RECORD=2|OwnerIndex=144|OwnerPartId=1|FormalType=1|Electrical=4|PinConglomerate=51|PinLength=10|Location.X=650|Location.Y=650|Name=2|Designator=2|PinPropagationDelay=0.000000E+000
|RECORD=2|OwnerIndex=144|OwnerPartId=1|FormalType=1|Electrical=4|PinConglomerate=51|PinLength=10|Location.X=660|Location.Y=650|Name=3|Designator=3|PinPropagationDelay=0.000000E+000
|RECORD=2|OwnerIndex=144|OwnerPartId=1|FormalType=1|Electrical=4|PinConglomerate=51|PinLength=10|Location.X=670|Location.Y=650|Name=4|Designator=4|PinPropagationDelay=0.000000E+000
|RECORD=6|OwnerIndex=144|IsNotAccesible=T|IndexInSheet=7|OwnerPartId=1|LineWidth=1|Color=16711680|LocationCount=5|X1=640|Y1=650|X2=640|Y2=690|X3=680|Y3=690|X4=680|Y4=650|X5=640|Y5=650
|RECORD=6|OwnerIndex=144|IsNotAccesible=T|IndexInSheet=8|OwnerPartId=1|LineWidth=1|Color=16711680|LocationCount=2|X1=640|Y1=670|X2=656|Y2=670
|RECORD=41|OwnerIndex=144|IndexInSheet=9|OwnerPartId=-1|Location.X=628|Location.Y=691|Color=8388608|FontID=1|IsHidden=T|Text=ThroughHole|Name=Mounting Technology
|RECORD=41|OwnerIndex=144|IndexInSheet=10|OwnerPartId=-1|Location.X=628|Location.Y=691|Color=8388608|FontID=1|IsHidden=T|Text=ThroughHole,RightAngle|Name=Mounting Type
|RECORD=41|OwnerIndex=144|IndexInSheet=11|OwnerPartId=-1|Location.X=628|Location.Y=691|Color=8388608|FontID=1|IsHidden=T|Text=-|Name=Cable Group
|RECORD=41|OwnerIndex=144|IndexInSheet=12|OwnerPartId=-1|Location.X=628|Location.Y=691|Color=8388608|FontID=1|IsHidden=T|Text=901-143-6RFXMountingHole|Name=Catalog Drawings
|RECORD=41|OwnerIndex=144|IndexInSheet=13|OwnerPartId=-1|Location.X=628|Location.Y=691|Color=8388608|FontID=1|IsHidden=T|Text=901-143-6RFX.igs|Name=3D Model
|RECORD=41|OwnerIndex=144|IndexInSheet=14|OwnerPartId=-1|Location.X=628|Location.Y=691|Color=8388608|FontID=1|IsHidden=T|Text=-|Name=Series
|RECORD=41|OwnerIndex=144|IndexInSheet=15|OwnerPartId=-1|Location.X=628|Location.Y=691|Color=8388608|FontID=1|IsHidden=T|Text=5-Pin Through Hole Device, Body 7 x 7 mm, Pitch 2.54 mm|Name=Package Description
|RECORD=41|OwnerIndex=144|IndexInSheet=16|OwnerPartId=-1|Location.X=628|Location.Y=691|Color=8388608|FontID=1|IsHidden=T|Text=901-143-6RFX|Name=Package Reference
|RECORD=41|OwnerIndex=144|IndexInSheet=17|OwnerPartId=-1|Location.X=628|Location.Y=691|Color=8388608|FontID=1|IsHidden=T|Text=Brass|Name=Body Material
|RECORD=41|OwnerIndex=144|IndexInSheet=18|OwnerPartId=-1|Location.X=628|Location.Y=691|Color=8388608|FontID=1|IsHidden=T|Text=-|Name=Voltage Rating
|RECORD=41|OwnerIndex=144|IndexInSheet=19|OwnerPartId=-1|Location.X=628|Location.Y=691|Color=8388608|FontID=1|IsHidden=T|Text=1|Name=Standard Package
|RECORD=41|OwnerIndex=144|IndexInSheet=20|OwnerPartId=-1|Location.X=628|Location.Y=691|Color=8388608|FontID=1|IsHidden=T|Text=Jack,FemaleSocket|Name=Connector Type
|RECORD=41|OwnerIndex=144|IndexInSheet=21|OwnerPartId=-1|Location.X=628|Location.Y=691|Color=8388608|FontID=1|IsHidden=T|Text=Threaded|Name=Fastening Type
|RECORD=41|OwnerIndex=144|IndexInSheet=22|OwnerPartId=-1|Location.X=628|Location.Y=691|Color=8388608|FontID=1|IsHidden=T|Text=Gold|Name=Housing Color
|RECORD=41|OwnerIndex=144|IndexInSheet=23|OwnerPartId=-1|Location.X=628|Location.Y=691|Color=8388608|FontID=1|IsHidden=T|Text=Solder|Name=Shield Termination
|RECORD=41|OwnerIndex=144|IndexInSheet=24|OwnerPartId=-1|Location.X=628|Location.Y=691|Color=8388608|FontID=1|IsHidden=T|Text=901-143-6-RFX9011436RFXARFX1232|Name=Other Names
|RECORD=41|OwnerIndex=144|IndexInSheet=25|OwnerPartId=-1|Location.X=628|Location.Y=691|Color=8388608|FontID=6|IsHidden=T|Text=http://www.amphenolrf.com/downloads/dl/file/id/2712/product/3102/901_143_6rfx_customer_drawing.pdf|Name=Datasheet URL
|RECORD=41|OwnerIndex=144|IndexInSheet=26|OwnerPartId=-1|Location.X=628|Location.Y=691|Color=8388608|FontID=1|IsHidden=T|Text=CoaxialConnectors(RF)|Name=Family
|RECORD=41|OwnerIndex=144|IndexInSheet=27|OwnerPartId=-1|Location.X=628|Location.Y=691|Color=8388608|FontID=1|IsHidden=T|Text=SMA,RFX|Name=Online Catalog
|RECORD=41|OwnerIndex=144|IndexInSheet=28|OwnerPartId=-1|Location.X=628|Location.Y=691|Color=8388608|FontID=1|IsHidden=T|Text=18GHz|Name=Frequency - Max
|RECORD=41|OwnerIndex=144|IndexInSheet=29|OwnerPartId=-1|Location.X=628|Location.Y=691|Color=8388608|FontID=1|IsHidden=T|Text=Solder|Name=Contact Termination
|RECORD=41|OwnerIndex=144|IndexInSheet=30|OwnerPartId=-1|Location.X=628|Location.Y=691|Color=8388608|FontID=6|IsHidden=T|Text=http://www.amphenol.com/|Name=Manufacturer URL
|RECORD=41|OwnerIndex=144|IndexInSheet=31|OwnerPartId=-1|Location.X=628|Location.Y=691|Color=8388608|FontID=1|IsHidden=T|Text=Amphenol|Name=Manufacturer
|RECORD=41|OwnerIndex=144|IndexInSheet=32|OwnerPartId=-1|Location.X=628|Location.Y=691|Color=8388608|FontID=1|IsHidden=T|Text=-65°C~165°C|Name=Operating Temperature
|RECORD=41|OwnerIndex=144|IndexInSheet=33|OwnerPartId=-1|Location.X=628|Location.Y=691|Color=8388608|FontID=1|IsHidden=T|Text=Connectors,Interconnects|Name=Category
|RECORD=41|OwnerIndex=144|IndexInSheet=34|OwnerPartId=-1|Location.X=628|Location.Y=691|Color=8388608|FontID=1|IsHidden=T|Text=Bulk|Name=Packaging
|RECORD=41|OwnerIndex=144|IndexInSheet=35|OwnerPartId=-1|Location.X=628|Location.Y=691|Color=8388608|FontID=1|IsHidden=T|Text=Gold|Name=Body Finish
|RECORD=41|OwnerIndex=144|IndexInSheet=36|OwnerPartId=-1|Location.X=628|Location.Y=691|Color=8388608|FontID=1|IsHidden=T|Text=Polytetrafluoroethylene(PTFE)|Name=Dielectric Material
|RECORD=41|OwnerIndex=144|IndexInSheet=37|OwnerPartId=-1|Location.X=628|Location.Y=691|Color=8388608|FontID=1|IsHidden=T|Text=BerylliumCopper|Name=Center Contact Material
|RECORD=41|OwnerIndex=144|IndexInSheet=38|OwnerPartId=-1|Location.X=628|Location.Y=691|Color=8388608|FontID=1|IsHidden=T|Text=50Ohm|Name=Impedance
|RECORD=41|OwnerIndex=144|IndexInSheet=39|OwnerPartId=-1|Location.X=628|Location.Y=691|Color=8388608|FontID=1|IsHidden=T|Text=-|Name=Features
|RECORD=41|OwnerIndex=144|IndexInSheet=40|OwnerPartId=-1|Location.X=628|Location.Y=691|Color=8388608|FontID=1|IsHidden=T|Text=SMA|Name=Connector Style
|RECORD=41|OwnerIndex=144|IndexInSheet=41|OwnerPartId=-1|Location.X=628|Location.Y=691|Color=8388608|FontID=1|IsHidden=T|Text=Gold|Name=Center Contact Plating
|RECORD=41|OwnerIndex=144|IndexInSheet=42|OwnerPartId=-1|Location.X=628|Location.Y=691|Color=8388608|FontID=1|IsHidden=T|Text=Rev. C, 06/2010|Name=Datasheet Version
|RECORD=41|OwnerIndex=144|IndexInSheet=43|OwnerPartId=-1|Location.X=628|Location.Y=691|Color=8388608|FontID=1|IsHidden=T|Text=-|Name=Ingress Protection
|RECORD=34|OwnerIndex=144|IndexInSheet=-1|OwnerPartId=-1|Location.X=639|Location.Y=691|Color=8388608|FontID=1|Text=AN1|Name=Designator|ReadOnlyState=1
|RECORD=41|OwnerIndex=144|IndexInSheet=-1|OwnerPartId=-1|Location.X=690|Location.Y=640|Color=8388608|FontID=1|Text=901-143-6RFX|Name=Comment
|RECORD=44|OwnerIndex=144
|RECORD=45|OwnerIndex=196|IndexInSheet=-1|Description=THD, 5-Leads, Body 7x7mm, Pitch 2.54mm|UseComponentLibrary=T|ModelName=AMPH-901-143-6RFX_V|ModelType=PCBLIB|DatafileCount=1|ModelDatafileEntity0=AMPH-901-143-6RFX_V|ModelDatafileKind0=PCBLib|IsCurrent=T|DatalinksLocked=T|DatabaseDatalinksLocked=T
|RECORD=46|OwnerIndex=197
|RECORD=48|OwnerIndex=197
|RECORD=41|OwnerIndex=199|IndexInSheet=-1|OwnerPartId=-1|Color=8388608|FontID=1|Text=2D|Name=Available Preview Images
|RECORD=17|IndexInSheet=38|OwnerPartId=-1|Style=4|ShowNetName=T|Location.X=710|Location.Y=710|Orientation=3|Color=128|FontID=1|Text=GND
|RECORD=1|LibReference=RES-2|ComponentDescription=General Purpose Chip Resistor, 49.9 Ohm, +/- 1%, -55 to 155 degC, 0603 (1608 Metric), RoHS, Tape and Reel|PartCount=2|DisplayModeCount=1|IndexInSheet=39|OwnerPartId=-1|Location.X=545|Location.Y=750|CurrentPartId=1|LibraryPath=*|SourceLibraryName=Altium Content Vault|TargetFileName=*|AreaColor=11599871|Color=128|PartIDLocked=T|DesignItemId=CMP-1659-00036-1|AllPinCount=2
|RECORD=2|OwnerIndex=202|OwnerPartId=1|FormalType=1|Electrical=4|PinConglomerate=32|PinLength=10|Location.X=565|Location.Y=750|Name=2|Designator=2|PinPropagationDelay=0.000000E+000
|RECORD=2|OwnerIndex=202|OwnerPartId=1|FormalType=1|Electrical=4|PinConglomerate=34|PinLength=10|Location.X=545|Location.Y=750|Name=1|Designator=1|PinPropagationDelay=0.000000E+000
|RECORD=6|OwnerIndex=202|IsNotAccesible=T|IndexInSheet=2|OwnerPartId=1|LineWidth=1|Color=16711680|LocationCount=10|X1=565|Y1=750|X2=561|Y2=750|X3=560|Y3=748|X4=558|Y4=752|X5=556|Y5=748|X6=554|Y6=752|X7=552|Y7=748|X8=550|Y8=752|X9=549|Y9=750|X10=545|Y10=750
|RECORD=41|OwnerIndex=202|IndexInSheet=3|OwnerPartId=-1|Location.X=533|Location.Y=765|Color=8388608|FontID=1|IsHidden=T|Text=0603|Name=PackageReference
|RECORD=41|OwnerIndex=202|IndexInSheet=4|OwnerPartId=-1|Location.X=533|Location.Y=765|Color=8388608|FontID=1|IsHidden=T|Text=Tray|Name=Packaging
|RECORD=41|OwnerIndex=202|IndexInSheet=5|OwnerPartId=-1|Location.X=533|Location.Y=765|Color=8388608|FontID=1|IsHidden=T|Text=Datasheet|Name=ComponentLink2Description
|RECORD=41|OwnerIndex=202|IndexInSheet=6|OwnerPartId=-1|Location.X=533|Location.Y=765|Color=8388608|FontID=1|IsHidden=T|Text=Manufacturer URL|Name=ComponentLink1Description
|RECORD=41|OwnerIndex=202|IndexInSheet=7|OwnerPartId=-1|Location.X=533|Location.Y=765|Color=8388608|FontID=6|IsHidden=T|Text=https://datasheet.ciiva.com/11808/0900766b80f96399-11808223.pdf|Name=ComponentLink2URL
|RECORD=41|OwnerIndex=202|IndexInSheet=8|OwnerPartId=-1|Location.X=533|Location.Y=765|Color=8388608|FontID=1|IsHidden=T|Text=true|Name=RoHSCompliant
|RECORD=41|OwnerIndex=202|IndexInSheet=9|OwnerPartId=-1|Location.X=533|Location.Y=765|Color=8388608|FontID=1|IsHidden=T|Text=85 degC|Name=Max Operating Temperature
|RECORD=41|OwnerIndex=202|IndexInSheet=10|OwnerPartId=-1|Location.X=533|Location.Y=765|Color=8388608|FontID=1|IsHidden=T|Text=3.63 V|Name=Max Supply Voltage
|RECORD=41|OwnerIndex=202|IndexInSheet=11|OwnerPartId=-1|Location.X=533|Location.Y=765|Color=8388608|FontID=6|IsHidden=T|Text=http://www.yageo.com/|Name=ComponentLink1URL
|RECORD=41|OwnerIndex=202|IndexInSheet=12|OwnerPartId=-1|Location.X=533|Location.Y=765|Color=8388608|FontID=1|IsHidden=T|Text=2-Pin Surface Mount Device, Body 1.6 x 0.8 mm|Name=PackageDescription
|RECORD=41|OwnerIndex=202|IndexInSheet=13|OwnerPartId=-1|Location.X=533|Location.Y=765|Color=8388608|FontID=1|IsHidden=T|Text=LQFP|Name=Case\Package
|RECORD=41|OwnerIndex=202|IndexInSheet=14|OwnerPartId=-1|Location.X=533|Location.Y=765|Color=8388608|FontID=1|IsHidden=T|Text=Rev. 4, 04/2009|Name=DatasheetVersion
|RECORD=41|OwnerIndex=202|IndexInSheet=15|OwnerPartId=-1|Location.X=533|Location.Y=765|Color=8388608|FontID=1|IsHidden=T|Text=-40 degC|Name=Min Operating Temperature
|RECORD=41|OwnerIndex=202|IndexInSheet=16|OwnerPartId=-1|Location.X=533|Location.Y=765|Color=8388608|FontID=1|IsHidden=T|Text=SPI|Name=Interface
|RECORD=41|OwnerIndex=202|IndexInSheet=17|OwnerPartId=-1|Location.X=533|Location.Y=765|Color=8388608|FontID=1|IsHidden=T|Text=250|Name=Package Quantity
|RECORD=41|OwnerIndex=202|IndexInSheet=18|OwnerPartId=-1|Location.X=533|Location.Y=765|Color=8388608|FontID=1|IsHidden=T|Text=2.97 V|Name=Min Supply Voltage
|RECORD=41|OwnerIndex=202|IndexInSheet=19|OwnerPartId=-1|Location.X=533|Location.Y=765|Color=8388608|FontID=1|IsHidden=T|Text=48|Name=Pins
|RECORD=34|OwnerIndex=202|IndexInSheet=-1|OwnerPartId=-1|Location.X=544|Location.Y=753|Color=8388608|FontID=1|Text=R25|Name=Designator|ReadOnlyState=1
|RECORD=41|OwnerIndex=202|IndexInSheet=-1|OwnerPartId=-1|Location.X=544|Location.Y=737|Color=8388608|FontID=1|Text=49.9R|Name=Comment
|RECORD=44|OwnerIndex=202
|RECORD=45|OwnerIndex=227|IndexInSheet=-1|Description=Chip Resistor, 2-Leads, Body 1.70x0.90mm, IPC Medium Density|UseComponentLibrary=T|ModelName=RESC1608X55X25NL10T15|ModelType=PCBLIB|DatafileCount=1|ModelDatafileEntity0=RESC1608X55X25NL10T15|ModelDatafileKind0=PCBLib|IsCurrent=T|DatalinksLocked=T|DatabaseDatalinksLocked=T
|RECORD=46|OwnerIndex=228
|RECORD=48|OwnerIndex=228
|RECORD=41|OwnerIndex=230|IndexInSheet=-1|OwnerPartId=-1|Color=8388608|FontID=1|IsHidden=T|Text=2D|Name=Available Preview Images
|RECORD=45|OwnerIndex=227|IndexInSheet=-1|Description=Chip Resistor, 2-Leads, Body 1.70x0.90mm, IPC Low Density|UseComponentLibrary=T|ModelName=RESC1608X55X25ML10T15|ModelType=PCBLIB|DatafileCount=1|ModelDatafileEntity0=RESC1608X55X25ML10T15|ModelDatafileKind0=PCBLib|DatalinksLocked=T|DatabaseDatalinksLocked=T
|RECORD=46|OwnerIndex=232
|RECORD=48|OwnerIndex=232
|RECORD=41|OwnerIndex=234|IndexInSheet=-1|OwnerPartId=-1|Color=8388608|FontID=1|IsHidden=T|Text=2D|Name=Available Preview Images
|RECORD=45|OwnerIndex=227|IndexInSheet=-1|Description=Chip Resistor, 2-Leads, Body 1.70x0.90mm, IPC High Density|UseComponentLibrary=T|ModelName=RESC1608X55X25LL10T15|ModelType=PCBLIB|DatafileCount=1|ModelDatafileEntity0=RESC1608X55X25LL10T15|ModelDatafileKind0=PCBLib|DatalinksLocked=T|DatabaseDatalinksLocked=T
|RECORD=46|OwnerIndex=236
|RECORD=48|OwnerIndex=236
|RECORD=41|OwnerIndex=238|IndexInSheet=-1|OwnerPartId=-1|Color=8388608|FontID=1|IsHidden=T|Text=2D|Name=Available Preview Images
|RECORD=17|IndexInSheet=40|OwnerPartId=-1|ShowNetName=T|Location.X=270|Location.Y=750|Orientation=2|Color=255|FontID=1|Text=ANT1_OUT|IsCrossSheetConnector=T
|RECORD=1|LibReference=RES-2|ComponentDescription=Precision Thick Film Chip Resistor, 4.7 KOhm, +/- 1%, -55 to 155 degC, 0603 (1608 Metric), RoHS, Tape and Reel ERJ-3EKF4701V|PartCount=2|DisplayModeCount=1|IndexInSheet=41|OwnerPartId=-1|Location.X=280|Location.Y=810|Orientation=1|CurrentPartId=1|LibraryPath=*|SourceLibraryName=Altium Content Vault|TargetFileName=*|AreaColor=11599871|Color=128|PartIDLocked=T|DesignItemId=CMP-1012-00586-3|AllPinCount=2
|RECORD=2|OwnerIndex=241|OwnerPartId=1|FormalType=1|Electrical=4|PinConglomerate=33|PinLength=10|Location.X=280|Location.Y=830|Name=2|Designator=2|PinPropagationDelay=0.000000E+000
|RECORD=2|OwnerIndex=241|OwnerPartId=1|FormalType=1|Electrical=4|PinConglomerate=35|PinLength=10|Location.X=280|Location.Y=810|Name=1|Designator=1|PinPropagationDelay=0.000000E+000
|RECORD=6|OwnerIndex=241|IsNotAccesible=T|IndexInSheet=2|OwnerPartId=1|LineWidth=1|Color=16711680|LocationCount=10|X1=280|Y1=830|X2=280|Y2=826|X3=282|Y3=825|X4=278|Y4=823|X5=282|Y5=821|X6=278|Y6=819|X7=282|Y7=817|X8=278|Y8=815|X9=280|Y9=814|X10=280|Y10=810
|RECORD=41|OwnerIndex=241|IndexInSheet=3|OwnerPartId=-1|Location.X=277|Location.Y=842|Color=8388608|FontID=1|IsHidden=T|Text=220 Ohm|Name=Resistance
|RECORD=41|OwnerIndex=241|IndexInSheet=4|OwnerPartId=-1|Location.X=277|Location.Y=842|Color=8388608|FontID=1|IsHidden=T|Text=0603|Name=PackageReference
|RECORD=41|OwnerIndex=241|IndexInSheet=5|OwnerPartId=-1|Location.X=277|Location.Y=842|Color=8388608|FontID=1|IsHidden=T|Text=50 V|Name=Voltage Rating
|RECORD=41|OwnerIndex=241|IndexInSheet=6|OwnerPartId=-1|Location.X=277|Location.Y=842|Color=8388608|FontID=1|IsHidden=T|Text=125 degC|Name=Max Operating Temperature
|RECORD=41|OwnerIndex=241|IndexInSheet=7|OwnerPartId=-1|Location.X=277|Location.Y=842|Color=8388608|FontID=1|IsHidden=T|Text=4|Name=Elements
|RECORD=41|OwnerIndex=241|IndexInSheet=8|OwnerPartId=-1|Location.X=277|Location.Y=842|Color=8388608|FontID=1|IsHidden=T|Text=No SVHC|Name=REACH SVHC
|RECORD=41|OwnerIndex=241|IndexInSheet=9|OwnerPartId=-1|Location.X=277|Location.Y=842|Color=8388608|FontID=1|IsHidden=T|Text=0.063 inch|Name=Width
|RECORD=41|OwnerIndex=241|IndexInSheet=10|OwnerPartId=-1|Location.X=277|Location.Y=842|Color=8388608|FontID=1|IsHidden=T|Text=1205|Name=Case\Package
|RECORD=41|OwnerIndex=241|IndexInSheet=11|OwnerPartId=-1|Location.X=277|Location.Y=842|Color=8388608|FontID=1|IsHidden=T|Text=0.126 inch|Name=Length
|RECORD=41|OwnerIndex=241|IndexInSheet=12|OwnerPartId=-1|Location.X=277|Location.Y=842|Color=8388608|FontID=1|IsHidden=T|Text=0.024 inch|Name=Height
|RECORD=41|OwnerIndex=241|IndexInSheet=13|OwnerPartId=-1|Location.X=277|Location.Y=842|Color=8388608|FontID=1|IsHidden=T|Text=Surface Mount|Name=Mount
|RECORD=41|OwnerIndex=241|IndexInSheet=14|OwnerPartId=-1|Location.X=277|Location.Y=842|Color=8388608|FontID=1|IsHidden=T|Text=1|Name=Package Quantity
|RECORD=41|OwnerIndex=241|IndexInSheet=15|OwnerPartId=-1|Location.X=277|Location.Y=842|Color=8388608|FontID=1|IsHidden=T|Text=Apr-15|Name=DatasheetVersion
|RECORD=41|OwnerIndex=241|IndexInSheet=16|OwnerPartId=-1|Location.X=277|Location.Y=842|Color=8388608|FontID=1|IsHidden=T|Text=Manufacturer URL|Name=ComponentLink1Description
|RECORD=41|OwnerIndex=241|IndexInSheet=17|OwnerPartId=-1|Location.X=277|Location.Y=842|Color=8388608|FontID=1|IsHidden=T|Text=-55 degC|Name=Min Operating Temperature
|RECORD=41|OwnerIndex=241|IndexInSheet=18|OwnerPartId=-1|Location.X=277|Location.Y=842|Color=8388608|FontID=1|IsHidden=T|Text=Tape and Reel|Name=Packaging
|RECORD=41|OwnerIndex=241|IndexInSheet=19|OwnerPartId=-1|Location.X=277|Location.Y=842|Color=8388608|FontID=1|IsHidden=T|Text=No|Name=Radiation Hardening
|RECORD=41|OwnerIndex=241|IndexInSheet=20|OwnerPartId=-1|Location.X=277|Location.Y=842|Color=8388608|FontID=6|IsHidden=T|Text=http://industrial.panasonic.com/cdbs/www-data/pdf/RDA0000/AOA0000C86.pdf|Name=ComponentLink2URL
|RECORD=41|OwnerIndex=241|IndexInSheet=21|OwnerPartId=-1|Location.X=277|Location.Y=842|Color=8388608|FontID=1|IsHidden=T|Text=3216|Name=Case Code (Metric)
|RECORD=41|OwnerIndex=241|IndexInSheet=22|OwnerPartId=-1|Location.X=277|Location.Y=842|Color=8388608|FontID=1|IsHidden=T|Text=8|Name=Pins
|RECORD=41|OwnerIndex=241|IndexInSheet=23|OwnerPartId=-1|Location.X=277|Location.Y=842|Color=8388608|FontID=1|IsHidden=T|Text=1206|Name=Case Code (Imperial)
|RECORD=41|OwnerIndex=241|IndexInSheet=24|OwnerPartId=-1|Location.X=277|Location.Y=842|Color=8388608|FontID=1|IsHidden=T|Text=Thick Film|Name=Type (Resistor)
|RECORD=41|OwnerIndex=241|IndexInSheet=25|OwnerPartId=-1|Location.X=277|Location.Y=842|Color=8388608|FontID=1|IsHidden=T|Text=true|Name=RoHSCompliant
|RECORD=41|OwnerIndex=241|IndexInSheet=26|OwnerPartId=-1|Location.X=277|Location.Y=842|Color=8388608|FontID=1|IsHidden=T|Text=5%|Name=Tolerance
|RECORD=41|OwnerIndex=241|IndexInSheet=27|OwnerPartId=-1|Location.X=277|Location.Y=842|Color=8388608|FontID=1|IsHidden=T|Text=Datasheet|Name=ComponentLink2Description
|RECORD=41|OwnerIndex=241|IndexInSheet=28|OwnerPartId=-1|Location.X=277|Location.Y=842|Color=8388608|FontID=1|IsHidden=T|Text=2-Pin Surface Mount Device, Body 1.6 x 0.85 mm|Name=PackageDescription
|RECORD=41|OwnerIndex=241|IndexInSheet=29|OwnerPartId=-1|Location.X=277|Location.Y=842|Color=8388608|FontID=6|IsHidden=T|Text=http://www.panasonic.com/|Name=ComponentLink1URL
|RECORD=41|OwnerIndex=241|IndexInSheet=30|OwnerPartId=-1|Location.X=277|Location.Y=842|Color=8388608|FontID=1|IsHidden=T|Text=250 mW|Name=Power Rating
|RECORD=34|OwnerIndex=241|IndexInSheet=-1|OwnerPartId=-1|Location.X=283|Location.Y=821|Color=8388608|FontID=1|Text=R14|Name=Designator|ReadOnlyState=1
|RECORD=41|OwnerIndex=241|IndexInSheet=-1|OwnerPartId=-1|Location.X=283|Location.Y=811|Color=8388608|FontID=1|Text=4.7K|Name=Comment
|RECORD=44|OwnerIndex=241
|RECORD=45|OwnerIndex=277|IndexInSheet=-1|Description=Chip Resistor, 2-Leads, Body 1.75x0.95mm, IPC Medium Density|UseComponentLibrary=T|ModelName=RESC1608X55X30NL15T15|ModelType=PCBLIB|DatafileCount=1|ModelDatafileEntity0=RESC1608X55X30NL15T15|ModelDatafileKind0=PCBLib|IsCurrent=T|DatalinksLocked=T|DatabaseDatalinksLocked=T
|RECORD=46|OwnerIndex=278
|RECORD=48|OwnerIndex=278
|RECORD=41|OwnerIndex=280|IndexInSheet=-1|OwnerPartId=-1|Color=8388608|FontID=1|IsHidden=T|Text=2D|Name=Available Preview Images
|RECORD=45|OwnerIndex=277|IndexInSheet=-1|Description=Chip Resistor, 2-Leads, Body 1.75x0.95mm, IPC Low Density|UseComponentLibrary=T|ModelName=RESC1608X55X30ML15T15|ModelType=PCBLIB|DatafileCount=1|ModelDatafileEntity0=RESC1608X55X30ML15T15|ModelDatafileKind0=PCBLib|DatalinksLocked=T|DatabaseDatalinksLocked=T
|RECORD=46|OwnerIndex=282
|RECORD=48|OwnerIndex=282
|RECORD=41|OwnerIndex=284|IndexInSheet=-1|OwnerPartId=-1|Color=8388608|FontID=1|IsHidden=T|Text=2D|Name=Available Preview Images
|RECORD=45|OwnerIndex=277|IndexInSheet=-1|Description=Chip Resistor, 2-Leads, Body 1.75x0.95mm, IPC High Density|UseComponentLibrary=T|ModelName=RESC1608X55X30LL15T15|ModelType=PCBLIB|DatafileCount=1|ModelDatafileEntity0=RESC1608X55X30LL15T15|ModelDatafileKind0=PCBLib|DatalinksLocked=T|DatabaseDatalinksLocked=T
|RECORD=46|OwnerIndex=286
|RECORD=48|OwnerIndex=286
|RECORD=41|OwnerIndex=288|IndexInSheet=-1|OwnerPartId=-1|Color=8388608|FontID=1|IsHidden=T|Text=2D|Name=Available Preview Images
|RECORD=1|LibReference=RES-2|ComponentDescription=Precision Thick Film Chip Resistor, 4.7 KOhm, +/- 1%, -55 to 155 degC, 0603 (1608 Metric), RoHS, Tape and Reel ERJ-3EKF4701V|PartCount=2|DisplayModeCount=1|IndexInSheet=42|OwnerPartId=-1|Location.X=310|Location.Y=810|Orientation=1|CurrentPartId=1|LibraryPath=*|SourceLibraryName=Altium Content Vault|TargetFileName=*|AreaColor=11599871|Color=128|PartIDLocked=T|DesignItemId=CMP-1012-00586-3|AllPinCount=2
|RECORD=2|OwnerIndex=290|OwnerPartId=1|FormalType=1|Electrical=4|PinConglomerate=33|PinLength=10|Location.X=310|Location.Y=830|Name=2|Designator=2|PinPropagationDelay=0.000000E+000
|RECORD=2|OwnerIndex=290|OwnerPartId=1|FormalType=1|Electrical=4|PinConglomerate=35|PinLength=10|Location.X=310|Location.Y=810|Name=1|Designator=1|PinPropagationDelay=0.000000E+000
|RECORD=6|OwnerIndex=290|IsNotAccesible=T|IndexInSheet=2|OwnerPartId=1|LineWidth=1|Color=16711680|LocationCount=10|X1=310|Y1=830|X2=310|Y2=826|X3=312|Y3=825|X4=308|Y4=823|X5=312|Y5=821|X6=308|Y6=819|X7=312|Y7=817|X8=308|Y8=815|X9=310|Y9=814|X10=310|Y10=810
|RECORD=41|OwnerIndex=290|IndexInSheet=3|OwnerPartId=-1|Location.X=307|Location.Y=842|Color=8388608|FontID=1|IsHidden=T|Text=220 Ohm|Name=Resistance
|RECORD=41|OwnerIndex=290|IndexInSheet=4|OwnerPartId=-1|Location.X=307|Location.Y=842|Color=8388608|FontID=1|IsHidden=T|Text=0603|Name=PackageReference
|RECORD=41|OwnerIndex=290|IndexInSheet=5|OwnerPartId=-1|Location.X=307|Location.Y=842|Color=8388608|FontID=1|IsHidden=T|Text=50 V|Name=Voltage Rating
|RECORD=41|OwnerIndex=290|IndexInSheet=6|OwnerPartId=-1|Location.X=307|Location.Y=842|Color=8388608|FontID=1|IsHidden=T|Text=125 degC|Name=Max Operating Temperature
|RECORD=41|OwnerIndex=290|IndexInSheet=7|OwnerPartId=-1|Location.X=307|Location.Y=842|Color=8388608|FontID=1|IsHidden=T|Text=4|Name=Elements
|RECORD=41|OwnerIndex=290|IndexInSheet=8|OwnerPartId=-1|Location.X=307|Location.Y=842|Color=8388608|FontID=1|IsHidden=T|Text=No SVHC|Name=REACH SVHC
|RECORD=41|OwnerIndex=290|IndexInSheet=9|OwnerPartId=-1|Location.X=307|Location.Y=842|Color=8388608|FontID=1|IsHidden=T|Text=0.063 inch|Name=Width
|RECORD=41|OwnerIndex=290|IndexInSheet=10|OwnerPartId=-1|Location.X=307|Location.Y=842|Color=8388608|FontID=1|IsHidden=T|Text=1205|Name=Case\Package
|RECORD=41|OwnerIndex=290|IndexInSheet=11|OwnerPartId=-1|Location.X=307|Location.Y=842|Color=8388608|FontID=1|IsHidden=T|Text=0.126 inch|Name=Length
|RECORD=41|OwnerIndex=290|IndexInSheet=12|OwnerPartId=-1|Location.X=307|Location.Y=842|Color=8388608|FontID=1|IsHidden=T|Text=0.024 inch|Name=Height
|RECORD=41|OwnerIndex=290|IndexInSheet=13|OwnerPartId=-1|Location.X=307|Location.Y=842|Color=8388608|FontID=1|IsHidden=T|Text=Surface Mount|Name=Mount
|RECORD=41|OwnerIndex=290|IndexInSheet=14|OwnerPartId=-1|Location.X=307|Location.Y=842|Color=8388608|FontID=1|IsHidden=T|Text=1|Name=Package Quantity
|RECORD=41|OwnerIndex=290|IndexInSheet=15|OwnerPartId=-1|Location.X=307|Location.Y=842|Color=8388608|FontID=1|IsHidden=T|Text=Apr-15|Name=DatasheetVersion
|RECORD=41|OwnerIndex=290|IndexInSheet=16|OwnerPartId=-1|Location.X=307|Location.Y=842|Color=8388608|FontID=1|IsHidden=T|Text=Manufacturer URL|Name=ComponentLink1Description
|RECORD=41|OwnerIndex=290|IndexInSheet=17|OwnerPartId=-1|Location.X=307|Location.Y=842|Color=8388608|FontID=1|IsHidden=T|Text=-55 degC|Name=Min Operating Temperature
|RECORD=41|OwnerIndex=290|IndexInSheet=18|OwnerPartId=-1|Location.X=307|Location.Y=842|Color=8388608|FontID=1|IsHidden=T|Text=Tape and Reel|Name=Packaging
|RECORD=41|OwnerIndex=290|IndexInSheet=19|OwnerPartId=-1|Location.X=307|Location.Y=842|Color=8388608|FontID=1|IsHidden=T|Text=No|Name=Radiation Hardening
|RECORD=41|OwnerIndex=290|IndexInSheet=20|OwnerPartId=-1|Location.X=307|Location.Y=842|Color=8388608|FontID=6|IsHidden=T|Text=http://industrial.panasonic.com/cdbs/www-data/pdf/RDA0000/AOA0000C86.pdf|Name=ComponentLink2URL
|RECORD=41|OwnerIndex=290|IndexInSheet=21|OwnerPartId=-1|Location.X=307|Location.Y=842|Color=8388608|FontID=1|IsHidden=T|Text=3216|Name=Case Code (Metric)
|RECORD=41|OwnerIndex=290|IndexInSheet=22|OwnerPartId=-1|Location.X=307|Location.Y=842|Color=8388608|FontID=1|IsHidden=T|Text=8|Name=Pins
|RECORD=41|OwnerIndex=290|IndexInSheet=23|OwnerPartId=-1|Location.X=307|Location.Y=842|Color=8388608|FontID=1|IsHidden=T|Text=1206|Name=Case Code (Imperial)
|RECORD=41|OwnerIndex=290|IndexInSheet=24|OwnerPartId=-1|Location.X=307|Location.Y=842|Color=8388608|FontID=1|IsHidden=T|Text=Thick Film|Name=Type (Resistor)
|RECORD=41|OwnerIndex=290|IndexInSheet=25|OwnerPartId=-1|Location.X=307|Location.Y=842|Color=8388608|FontID=1|IsHidden=T|Text=true|Name=RoHSCompliant
|RECORD=41|OwnerIndex=290|IndexInSheet=26|OwnerPartId=-1|Location.X=307|Location.Y=842|Color=8388608|FontID=1|IsHidden=T|Text=5%|Name=Tolerance
|RECORD=41|OwnerIndex=290|IndexInSheet=27|OwnerPartId=-1|Location.X=307|Location.Y=842|Color=8388608|FontID=1|IsHidden=T|Text=Datasheet|Name=ComponentLink2Description
|RECORD=41|OwnerIndex=290|IndexInSheet=28|OwnerPartId=-1|Location.X=307|Location.Y=842|Color=8388608|FontID=1|IsHidden=T|Text=2-Pin Surface Mount Device, Body 1.6 x 0.85 mm|Name=PackageDescription
|RECORD=41|OwnerIndex=290|IndexInSheet=29|OwnerPartId=-1|Location.X=307|Location.Y=842|Color=8388608|FontID=6|IsHidden=T|Text=http://www.panasonic.com/|Name=ComponentLink1URL
|RECORD=41|OwnerIndex=290|IndexInSheet=30|OwnerPartId=-1|Location.X=307|Location.Y=842|Color=8388608|FontID=1|IsHidden=T|Text=250 mW|Name=Power Rating
|RECORD=34|OwnerIndex=290|IndexInSheet=-1|OwnerPartId=-1|Location.X=313|Location.Y=821|Color=8388608|FontID=1|Text=R15|Name=Designator|ReadOnlyState=1
|RECORD=41|OwnerIndex=290|IndexInSheet=-1|OwnerPartId=-1|Location.X=313|Location.Y=811|Color=8388608|FontID=1|Text=4.7K|Name=Comment
|RECORD=44|OwnerIndex=290
|RECORD=45|OwnerIndex=326|IndexInSheet=-1|Description=Chip Resistor, 2-Leads, Body 1.75x0.95mm, IPC Medium Density|UseComponentLibrary=T|ModelName=RESC1608X55X30NL15T15|ModelType=PCBLIB|DatafileCount=1|ModelDatafileEntity0=RESC1608X55X30NL15T15|ModelDatafileKind0=PCBLib|IsCurrent=T|DatalinksLocked=T|DatabaseDatalinksLocked=T
|RECORD=46|OwnerIndex=327
|RECORD=48|OwnerIndex=327
|RECORD=41|OwnerIndex=329|IndexInSheet=-1|OwnerPartId=-1|Color=8388608|FontID=1|IsHidden=T|Text=2D|Name=Available Preview Images
|RECORD=45|OwnerIndex=326|IndexInSheet=-1|Description=Chip Resistor, 2-Leads, Body 1.75x0.95mm, IPC Low Density|UseComponentLibrary=T|ModelName=RESC1608X55X30ML15T15|ModelType=PCBLIB|DatafileCount=1|ModelDatafileEntity0=RESC1608X55X30ML15T15|ModelDatafileKind0=PCBLib|DatalinksLocked=T|DatabaseDatalinksLocked=T
|RECORD=46|OwnerIndex=331
|RECORD=48|OwnerIndex=331
|RECORD=41|OwnerIndex=333|IndexInSheet=-1|OwnerPartId=-1|Color=8388608|FontID=1|IsHidden=T|Text=2D|Name=Available Preview Images
|RECORD=45|OwnerIndex=326|IndexInSheet=-1|Description=Chip Resistor, 2-Leads, Body 1.75x0.95mm, IPC High Density|UseComponentLibrary=T|ModelName=RESC1608X55X30LL15T15|ModelType=PCBLIB|DatafileCount=1|ModelDatafileEntity0=RESC1608X55X30LL15T15|ModelDatafileKind0=PCBLib|DatalinksLocked=T|DatabaseDatalinksLocked=T
|RECORD=46|OwnerIndex=335
|RECORD=48|OwnerIndex=335
|RECORD=41|OwnerIndex=337|IndexInSheet=-1|OwnerPartId=-1|Color=8388608|FontID=1|IsHidden=T|Text=2D|Name=Available Preview Images
|RECORD=17|IndexInSheet=43|OwnerPartId=-1|ShowNetName=T|Location.X=280|Location.Y=840|Orientation=1|Color=128|FontID=1|Text=+3.3V
|RECORD=17|IndexInSheet=44|OwnerPartId=-1|ShowNetName=T|Location.X=310|Location.Y=840|Orientation=1|Color=128|FontID=1|Text=+3.3V
|RECORD=17|IndexInSheet=45|OwnerPartId=-1|ShowNetName=T|Location.X=270|Location.Y=695|Orientation=2|Color=255|FontID=1|Text=ANT1_IN|IsCrossSheetConnector=T
|RECORD=1|LibReference=CAP|ComponentDescription=C0603X104K5RACAUTO|PartCount=2|DisplayModeCount=2|IndexInSheet=46|OwnerPartId=-1|Location.X=350|Location.Y=650|Orientation=3|CurrentPartId=1|SourceLibraryName=Altium Content Vault|TargetFileName=*|AreaColor=11599871|Color=128|PartIDLocked=F|DesignItemId=CMP-2006-00003-1|AllPinCount=2
|RECORD=2|OwnerIndex=342|OwnerPartId=1|OwnerPartDisplayMode=1|FormalType=1|Electrical=4|PinConglomerate=33|PinLength=10|Location.X=340|Location.Y=650|Name=1|Designator=1|PinPropagationDelay=0.000000E+000
|RECORD=2|OwnerIndex=342|OwnerPartId=1|OwnerPartDisplayMode=1|FormalType=1|Electrical=4|PinConglomerate=35|PinLength=10|Location.X=340|Location.Y=640|Name=2|Designator=2|PinPropagationDelay=0.000000E+000
|RECORD=13|OwnerIndex=342|IsNotAccesible=T|IndexInSheet=2|OwnerPartId=1|OwnerPartDisplayMode=1|Location.X=332|Location.Y=650|Corner.X=348|Corner.Y=650|LineWidth=1|Color=16711680
|RECORD=13|OwnerIndex=342|IsNotAccesible=T|IndexInSheet=3|OwnerPartId=1|OwnerPartDisplayMode=1|Location.X=340|Location.Y=646|Corner.X=340|Corner.Y=640|LineWidth=1|Color=16711680
|RECORD=12|OwnerIndex=342|IsNotAccesible=T|IndexInSheet=4|OwnerPartId=1|OwnerPartDisplayMode=1|Location.X=340|Location.Y=630|Radius=16|LineWidth=1|StartAngle=61.000|EndAngle=90.000|Color=16711680
|RECORD=12|OwnerIndex=342|IsNotAccesible=T|IndexInSheet=5|OwnerPartId=1|OwnerPartDisplayMode=1|Location.X=340|Location.Y=630|Radius=16|LineWidth=1|StartAngle=90.000|EndAngle=119.000|Color=16711680
|RECORD=2|OwnerIndex=342|OwnerPartId=1|FormalType=1|Electrical=4|PinConglomerate=33|PinLength=10|Location.X=340|Location.Y=650|Name=1|Designator=1|PinPropagationDelay=0.000000E+000
|RECORD=2|OwnerIndex=342|OwnerPartId=1|FormalType=1|Electrical=4|PinConglomerate=35|PinLength=10|Location.X=340|Location.Y=640|Name=2|Designator=2|PinPropagationDelay=0.000000E+000
|RECORD=13|OwnerIndex=342|IsNotAccesible=T|IndexInSheet=8|OwnerPartId=1|Location.X=348|Location.Y=643|Corner.X=332|Corner.Y=643|LineWidth=1|Color=16711680
|RECORD=13|OwnerIndex=342|IsNotAccesible=T|IndexInSheet=9|OwnerPartId=1|Location.X=332|Location.Y=647|Corner.X=348|Corner.Y=647|LineWidth=1|Color=16711680
|RECORD=6|OwnerIndex=342|IsNotAccesible=T|IndexInSheet=10|OwnerPartId=1|LineWidth=1|Color=16711680|LocationCount=2|X1=340|Y1=650|X2=340|Y2=647
|RECORD=6|OwnerIndex=342|IsNotAccesible=T|IndexInSheet=11|OwnerPartId=1|LineWidth=1|Color=16711680|LocationCount=2|X1=340|Y1=640|X2=340|Y2=643
|RECORD=41|OwnerIndex=342|IndexInSheet=12|OwnerPartId=-1|Location.X=331|Location.Y=662|Color=8388608|FontID=1|IsHidden=T|Text=Kemet|Name=Manufacturer
|RECORD=41|OwnerIndex=342|IndexInSheet=13|OwnerPartId=-1|Location.X=331|Location.Y=662|Color=8388608|FontID=1|IsHidden=T|Text=C0603X104K5RACAUTO|Name=Part Number
|RECORD=34|OwnerIndex=342|IndexInSheet=-1|OwnerPartId=-1|Location.X=349|Location.Y=637|Color=8388608|FontID=1|Text=C26|Name=Designator|ReadOnlyState=1
|RECORD=41|OwnerIndex=342|IndexInSheet=-1|OwnerPartId=-1|Location.X=349|Location.Y=623|Color=8388608|FontID=1|Text=0.1uF|Name=Comment
|RECORD=44|OwnerIndex=342
|RECORD=45|OwnerIndex=363|IndexInSheet=-1|Description=Chip Capacitor, 2-Leads, Body 1.60x0.80mm, IPC Low Density|UseComponentLibrary=T|ModelName=CAPC1608X87X45ML20T05|ModelType=PCBLIB|DatafileCount=1|ModelDatafileEntity0=CAPC1608X87X45ML20T05|ModelDatafileKind0=PCBLib|IsCurrent=T|DatalinksLocked=T|DatabaseDatalinksLocked=T
|RECORD=46|OwnerIndex=364
|RECORD=48|OwnerIndex=364
|RECORD=41|OwnerIndex=366|IndexInSheet=-1|OwnerPartId=-1|Color=8388608|FontID=1|Text=2D|Name=Available Preview Images
|RECORD=45|OwnerIndex=363|IndexInSheet=-1|Description=Chip Capacitor, 2-Leads, Body 1.60x0.80mm, IPC High Density|UseComponentLibrary=T|ModelName=CAPC1608X87X45LL20T05|ModelType=PCBLIB|DatafileCount=1|ModelDatafileEntity0=CAPC1608X87X45LL20T05|ModelDatafileKind0=PCBLib|DatalinksLocked=T|DatabaseDatalinksLocked=T
|RECORD=46|OwnerIndex=368
|RECORD=48|OwnerIndex=368
|RECORD=41|OwnerIndex=370|IndexInSheet=-1|OwnerPartId=-1|Color=8388608|FontID=1|Text=2D|Name=Available Preview Images
|RECORD=45|OwnerIndex=363|IndexInSheet=-1|Description=Chip Capacitor, 2-Leads, Body 1.60x0.80mm, IPC Medium Density|UseComponentLibrary=T|ModelName=CAPC1608X87X45NL20T05|ModelType=PCBLIB|DatafileCount=1|ModelDatafileEntity0=CAPC1608X87X45NL20T05|ModelDatafileKind0=PCBLib|DatalinksLocked=T|DatabaseDatalinksLocked=T
|RECORD=46|OwnerIndex=372
|RECORD=48|OwnerIndex=372
|RECORD=41|OwnerIndex=374|IndexInSheet=-1|OwnerPartId=-1|Color=8388608|FontID=1|Text=2D|Name=Available Preview Images
|RECORD=17|IndexInSheet=47|OwnerPartId=-1|Style=4|ShowNetName=T|Location.X=390|Location.Y=620|Orientation=3|Color=128|FontID=1|Text=GND
|RECORD=17|IndexInSheet=48|OwnerPartId=-1|Style=4|ShowNetName=T|Location.X=340|Location.Y=620|Orientation=3|Color=128|FontID=1|Text=GND
|RECORD=17|IndexInSheet=49|OwnerPartId=-1|ShowNetName=T|Location.X=340|Location.Y=840|Orientation=1|Color=128|FontID=1|Text=+3.3V
|RECORD=1|LibReference=WE-TVS-HS-4|ComponentDescription=TVS Diode WE-TVS-HS, VRWM=3.3V|PartCount=2|DisplayModeCount=1|IndexInSheet=50|OwnerPartId=-1|Location.X=580|Location.Y=560|Orientation=1|CurrentPartId=1|LibraryPath=*|SourceLibraryName=Altium Content Vault|TargetFileName=*|AreaColor=11599871|Color=128|PartIDLocked=F|DesignItemId=CMP-1486-00002-1|AllPinCount=4
|RECORD=14|OwnerIndex=379|IsNotAccesible=T|OwnerPartId=1|Location.X=574|Location.Y=537|Corner.X=614|Corner.Y=575|AreaColor=11599871|IsSolid=T|Transparent=T
|RECORD=6|OwnerIndex=379|IsNotAccesible=T|IndexInSheet=1|OwnerPartId=1|LineWidth=1|Color=16711680|LocationCount=4|X1=584|X1_Frac=10000|Y1=561|Y1_Frac=40000|X2=582|X2_Frac=10000|Y2=559|Y2_Frac=40000|X3=578|X3_Frac=10000|Y3=559|Y3_Frac=40000|X4=576|X4_Frac=10000|Y4=557|Y4_Frac=40000
|RECORD=7|OwnerIndex=379|IsNotAccesible=T|IndexInSheet=2|OwnerPartId=1|LineWidth=1|Color=16711680|AreaColor=16711680|IsSolid=T|LocationCount=3|X1=584|X1_Frac=90000|Y1=553|Y1_Frac=50000|X2=579|X2_Frac=90000|Y2=558|Y2_Frac=50000|X3=574|X3_Frac=90000|Y3=553|Y3_Frac=50000
|RECORD=12|OwnerIndex=379|IsNotAccesible=T|IndexInSheet=3|OwnerPartId=1|Location.X=591|Location.Y=558|Radius_Frac=63392|LineWidth=1|StartAngle=57.394|EndAngle=30.947
|RECORD=6|OwnerIndex=379|IsNotAccesible=T|IndexInSheet=4|OwnerPartId=1|LineWidth=1|LocationCount=2|X1=600|Y1=558|X2=591|Y2=558
|RECORD=7|OwnerIndex=379|IsNotAccesible=T|IndexInSheet=5|OwnerPartId=1|LineWidth=1|Color=16711680|AreaColor=16711680|LocationCount=3|X1=595|X1_Frac=90000|Y1=545|Y1_Frac=50000|X2=590|X2_Frac=90000|Y2=550|Y2_Frac=50000|X3=585|X3_Frac=90000|Y3=545|Y3_Frac=50000
|RECORD=6|OwnerIndex=379|IsNotAccesible=T|IndexInSheet=6|OwnerPartId=1|LineWidth=1|Color=16711680|LocationCount=2|X1=587|Y1=551|X2=594|X2_Frac=87402|Y2=551
|RECORD=7|OwnerIndex=379|IsNotAccesible=T|IndexInSheet=7|OwnerPartId=1|LineWidth=1|Color=16711680|AreaColor=16711680|LocationCount=3|X1=595|X1_Frac=90000|Y1=561|Y1_Frac=50000|X2=590|X2_Frac=90000|Y2=566|Y2_Frac=50000|X3=585|X3_Frac=90000|Y3=561|Y3_Frac=50000
|RECORD=6|OwnerIndex=379|IsNotAccesible=T|IndexInSheet=8|OwnerPartId=1|LineWidth=1|Color=16711680|LocationCount=2|X1=587|Y1=567|X2=594|X2_Frac=87402|Y2=567
|RECORD=6|OwnerIndex=379|IsNotAccesible=T|IndexInSheet=9|OwnerPartId=1|LineWidth=1|LocationCount=2|X1=591|Y1=551|X2=591|Y2=561
|RECORD=6|OwnerIndex=379|IsNotAccesible=T|IndexInSheet=10|OwnerPartId=1|LineWidth=1|LocationCount=2|X1=591|Y1=567|X2=591|Y2=573
|RECORD=6|OwnerIndex=379|IsNotAccesible=T|IndexInSheet=11|OwnerPartId=1|LineWidth=1|LocationCount=2|X1=580|Y1=560|X2=580|Y2=573
|RECORD=6|OwnerIndex=379|IsNotAccesible=T|IndexInSheet=12|OwnerPartId=1|LineWidth=1|LocationCount=2|X1=580|Y1=539|X2=580|Y2=553
|RECORD=6|OwnerIndex=379|IsNotAccesible=T|IndexInSheet=13|OwnerPartId=1|LineWidth=1|LocationCount=2|X1=591|Y1=539|X2=591|Y2=545
|RECORD=6|OwnerIndex=379|IsNotAccesible=T|IndexInSheet=14|OwnerPartId=1|LineWidth=1|LocationCount=2|X1=580|Y1=539|X2=608|Y2=539
|RECORD=6|OwnerIndex=379|IsNotAccesible=T|IndexInSheet=15|OwnerPartId=1|LineWidth=1|LocationCount=2|X1=580|Y1=573|X2=608|Y2=573
|RECORD=6|OwnerIndex=379|IsNotAccesible=T|IndexInSheet=16|OwnerPartId=1|LineWidth=1|LocationCount=2|X1=600|Y1=554|X2=600|Y2=540
|RECORD=2|OwnerIndex=379|OwnerPartId=1|FormalType=1|Electrical=4|PinConglomerate=51|PinLength=10|Location.X=580|Location.Y=540|Name=GND|Designator=1|PinPropagationDelay=0.000000E+000
|RECORD=2|OwnerIndex=379|OwnerPartId=1|FormalType=1|Electrical=4|PinConglomerate=51|PinLength=10|Location.X=600|Location.Y=540|Name=I/O1|Designator=2|PinPropagationDelay=0.000000E+000
|RECORD=2|OwnerIndex=379|OwnerPartId=1|FormalType=1|Electrical=4|PinConglomerate=49|PinLength=10|Location.X=600|Location.Y=570|Name=I/O2|Designator=3|PinPropagationDelay=0.000000E+000
|RECORD=2|OwnerIndex=379|OwnerPartId=1|FormalType=1|Electrical=4|PinConglomerate=49|PinLength=10|Location.X=580|Location.Y=570|Name=VDD|Designator=4|PinPropagationDelay=0.000000E+000
|RECORD=12|OwnerIndex=379|IsNotAccesible=T|IndexInSheet=21|OwnerPartId=1|Location.X=580|Location.Y=573|Radius_Frac=63392|LineWidth=1|StartAngle=57.394|EndAngle=30.947
|RECORD=12|OwnerIndex=379|IsNotAccesible=T|IndexInSheet=22|OwnerPartId=1|Location.X=580|Location.Y=539|Radius_Frac=63392|LineWidth=1|StartAngle=57.394|EndAngle=30.947
|RECORD=12|OwnerIndex=379|IsNotAccesible=T|IndexInSheet=23|OwnerPartId=1|Location.X=608|Location.Y=554|Radius_Frac=63392|LineWidth=1|StartAngle=57.394|EndAngle=30.947
|RECORD=6|OwnerIndex=379|IsNotAccesible=T|IndexInSheet=24|OwnerPartId=1|LineWidth=1|LocationCount=2|X1=600|Y1=554|X2=608|Y2=554
|RECORD=7|OwnerIndex=379|IsNotAccesible=T|IndexInSheet=25|OwnerPartId=1|LineWidth=1|Color=16711680|AreaColor=16711680|LocationCount=3|X1=612|X1_Frac=90000|Y1=545|Y1_Frac=50000|X2=607|X2_Frac=90000|Y2=550|Y2_Frac=50000|X3=602|X3_Frac=90000|Y3=545|Y3_Frac=50000
|RECORD=6|OwnerIndex=379|IsNotAccesible=T|IndexInSheet=26|OwnerPartId=1|LineWidth=1|Color=16711680|LocationCount=2|X1=604|Y1=551|X2=611|X2_Frac=87402|Y2=551
|RECORD=7|OwnerIndex=379|IsNotAccesible=T|IndexInSheet=27|OwnerPartId=1|LineWidth=1|Color=16711680|AreaColor=16711680|LocationCount=3|X1=612|X1_Frac=90000|Y1=561|Y1_Frac=50000|X2=607|X2_Frac=90000|Y2=566|Y2_Frac=50000|X3=602|X3_Frac=90000|Y3=561|Y3_Frac=50000
|RECORD=6|OwnerIndex=379|IsNotAccesible=T|IndexInSheet=28|OwnerPartId=1|LineWidth=1|Color=16711680|LocationCount=2|X1=604|Y1=567|X2=611|X2_Frac=87402|Y2=567
|RECORD=6|OwnerIndex=379|IsNotAccesible=T|IndexInSheet=29|OwnerPartId=1|LineWidth=1|LocationCount=2|X1=608|Y1=551|X2=608|Y2=561
|RECORD=6|OwnerIndex=379|IsNotAccesible=T|IndexInSheet=30|OwnerPartId=1|LineWidth=1|LocationCount=2|X1=608|Y1=567|X2=608|Y2=573
|RECORD=6|OwnerIndex=379|IsNotAccesible=T|IndexInSheet=31|OwnerPartId=1|LineWidth=1|LocationCount=2|X1=608|Y1=539|X2=608|Y2=545
|RECORD=12|OwnerIndex=379|IsNotAccesible=T|IndexInSheet=32|OwnerPartId=1|Location.X=591|Location.Y=573|Radius_Frac=63392|LineWidth=1|StartAngle=57.394|EndAngle=30.947
|RECORD=12|OwnerIndex=379|IsNotAccesible=T|IndexInSheet=33|OwnerPartId=1|Location.X=591|Location.Y=539|Radius_Frac=63392|LineWidth=1|StartAngle=57.394|EndAngle=30.947
|RECORD=6|OwnerIndex=379|IsNotAccesible=T|IndexInSheet=34|OwnerPartId=1|LineWidth=1|LocationCount=2|X1=600|Y1=558|X2=600|Y2=575
|RECORD=41|OwnerIndex=379|IndexInSheet=35|OwnerPartId=-1|Location.X=573|Location.X_Frac=90000|Location.Y=582|Color=8388608|FontID=1|IsHidden=T|Text=8240136|Name=PartNumber
|RECORD=41|OwnerIndex=379|IndexInSheet=36|OwnerPartId=-1|Location.X=573|Location.X_Frac=90000|Location.Y=582|Color=8388608|FontID=1|IsHidden=T|Text=Manufacturer URL|Name=ComponentLink1Description
|RECORD=41|OwnerIndex=379|IndexInSheet=37|OwnerPartId=-1|Location.X=573|Location.X_Frac=90000|Location.Y=582|Color=8388608|FontID=1|IsHidden=T|Text=Wuerth Elektronik|Name=Manufacturer
|RECORD=41|OwnerIndex=379|IndexInSheet=38|OwnerPartId=-1|Location.X=573|Location.X_Frac=90000|Location.Y=582|Color=8388608|FontID=1|IsHidden=T|Text=SOT143-4L|Name=PackageReference
|RECORD=41|OwnerIndex=379|IndexInSheet=39|OwnerPartId=-1|Location.X=573|Location.X_Frac=90000|Location.Y=582|Color=8388608|FontID=6|IsHidden=T|Text=http://www.we-online.com|Name=ComponentLink1URL
|RECORD=41|OwnerIndex=379|IndexInSheet=40|OwnerPartId=-1|Location.X=573|Location.X_Frac=90000|Location.Y=582|Color=8388608|FontID=1|IsHidden=T|Text=3.3V|Name=Reverse Stand Off Voltage
|RECORD=41|OwnerIndex=379|IndexInSheet=41|OwnerPartId=-1|Location.X=573|Location.X_Frac=90000|Location.Y=582|Color=8388608|FontID=1|IsHidden=T|Text=Datasheet|Name=ComponentLink2Description
|RECORD=41|OwnerIndex=379|IndexInSheet=42|OwnerPartId=-1|Location.X=573|Location.X_Frac=90000|Location.Y=582|Color=8388608|FontID=6|IsHidden=T|Text=http://katalog.we-online.de/kataloge/eisos/media/pdf/8240136.pdf|Name=ComponentLink2URL
|RECORD=34|OwnerIndex=379|IndexInSheet=-1|OwnerPartId=-1|Location.X=614|Location.Y=566|Color=8388608|FontID=1|Text=D1|Name=Designator|ReadOnlyState=1
|RECORD=41|OwnerIndex=379|IndexInSheet=-1|OwnerPartId=-1|Location.X=614|Location.Y=556|Color=8388608|FontID=1|Text=8240136|Name=Comment
|RECORD=44|OwnerIndex=379
|RECORD=45|OwnerIndex=429|IndexInSheet=-1|Description=SOT143-4L, 4-Leads, Body 2.95x2.4mm, Pitch 1.70/1.90mm|UseComponentLibrary=T|ModelName=SOT143-4L|ModelType=PCBLIB|DatafileCount=1|ModelDatafileEntity0=SOT143-4L|ModelDatafileKind0=PCBLib|IsCurrent=T|DatalinksLocked=T|DatabaseDatalinksLocked=T
|RECORD=46|OwnerIndex=430
|RECORD=48|OwnerIndex=430
|RECORD=41|OwnerIndex=432|IndexInSheet=-1|OwnerPartId=-1|Color=8388608|FontID=1|IsHidden=T|Text=2D|Name=Available Preview Images
|RECORD=1|LibReference=NC7WV125K8X|ComponentDescription=Integrated Circuit|PartCount=2|DisplayModeCount=1|IndexInSheet=51|OwnerPartId=-1|Location.X=1160|Location.Y=685|CurrentPartId=1|LibraryPath=*|SourceLibraryName=SamacSys.SchLib|TargetFileName=*|AreaColor=11599871|Color=128|PartIDLocked=T|DesignItemId=NC7WV125K8X|AllPinCount=8
|RECORD=41|OwnerIndex=434|OwnerPartId=-1|Location.X=1160|Location.Y=685|Color=8388608|FontID=6|IsHidden=T|Text=https://www.mouser.com/datasheet/2/308/NC7WV125-1301459.pdf|Name=Datasheet Link
|RECORD=41|OwnerIndex=434|IndexInSheet=1|OwnerPartId=-1|Location.X=1160|Location.Y=685|Color=8388608|FontID=1|IsHidden=T|Text=0.9mm|Name=Height
|RECORD=41|OwnerIndex=434|IndexInSheet=2|OwnerPartId=-1|Location.X=1160|Location.Y=685|Color=8388608|FontID=1|IsHidden=T|Text=ON Semiconductor|Name=Manufacturer_Name
|RECORD=41|OwnerIndex=434|IndexInSheet=3|OwnerPartId=-1|Location.X=1160|Location.Y=685|Color=8388608|FontID=1|IsHidden=T|Text=NC7WV125K8X|Name=Manufacturer_Part_Number
|RECORD=41|OwnerIndex=434|IndexInSheet=4|OwnerPartId=-1|Location.X=1160|Location.Y=685|Color=8388608|FontID=1|IsHidden=T|Text=512-NC7WV125K8X|Name=Mouser Part Number
|RECORD=41|OwnerIndex=434|IndexInSheet=5|OwnerPartId=-1|Location.X=1160|Location.Y=685|Color=8388608|FontID=6|IsHidden=T|Text=https://www.mouser.com/Search/Refine.aspx?Keyword=512-NC7WV125K8X|Name=Mouser Price/Stock
|RECORD=41|OwnerIndex=434|IndexInSheet=6|OwnerPartId=-1|Location.X=1160|Location.Y=685|Color=8388608|FontID=1|IsHidden=T|Text=NC7WV125K8X|Name=Arrow Part Number
|RECORD=41|OwnerIndex=434|IndexInSheet=7|OwnerPartId=-1|Location.X=1160|Location.Y=685|Color=8388608|FontID=6|IsHidden=T|Text=https://www.arrow.com/en/products/nc7wv125k8x/on-semiconductor|Name=Arrow Price/Stock
|RECORD=14|OwnerIndex=434|IsNotAccesible=T|IndexInSheet=8|OwnerPartId=1|Location.X=1180|Location.Y=660|Corner.X=1250|Corner.Y=785|LineWidth=1|Color=128|AreaColor=11599871|IsSolid=T
|RECORD=2|OwnerIndex=434|OwnerPartId=1|FormalType=1|Electrical=4|PinConglomerate=58|PinLength=20|Location.X=1180|Location.Y=775|Designator=1|SwapIDPart=Ž&Ž||PinPropagationDelay=0.000000E+000
|RECORD=2|OwnerIndex=434|OwnerPartId=1|FormalType=1|Electrical=4|PinConglomerate=58|PinLength=20|Location.X=1180|Location.Y=750|Designator=2|SwapIDPart=Ž&Ž||PinPropagationDelay=0.000000E+000
|RECORD=2|OwnerIndex=434|OwnerPartId=1|FormalType=1|Electrical=4|PinConglomerate=58|PinLength=20|Location.X=1180|Location.Y=695|Designator=3|SwapIDPart=Ž&Ž||PinPropagationDelay=0.000000E+000
|RECORD=2|OwnerIndex=434|OwnerPartId=1|FormalType=1|Electrical=4|PinConglomerate=58|PinLength=20|Location.X=1180|Location.Y=665|Name=GND|Designator=4|SwapIDPart=Ž&Ž||PinPropagationDelay=0.000000E+000
|RECORD=2|OwnerIndex=434|OwnerPartId=1|FormalType=1|Electrical=4|PinConglomerate=58|PinLength=20|Location.X=1180|Location.Y=675|Name=VCC|Designator=8|SwapIDPart=Ž&Ž||PinPropagationDelay=0.000000E+000
|RECORD=2|OwnerIndex=434|OwnerPartId=1|FormalType=1|Electrical=4|PinConglomerate=58|PinLength=20|Location.X=1180|Location.Y=720|Designator=7|SwapIDPart=Ž&Ž||PinPropagationDelay=0.000000E+000
|RECORD=2|OwnerIndex=434|OwnerPartId=1|FormalType=1|Electrical=4|PinConglomerate=56|PinLength=20|Location.X=1250|Location.Y=750|Designator=6|SwapIDPart=Ž&Ž||PinPropagationDelay=0.000000E+000
|RECORD=2|OwnerIndex=434|OwnerPartId=1|FormalType=1|Electrical=4|PinConglomerate=56|PinLength=20|Location.X=1250|Location.Y=695|Designator=5|SwapIDPart=Ž&Ž||PinPropagationDelay=0.000000E+000
|RECORD=6|OwnerIndex=434|IsNotAccesible=T|IndexInSheet=17|OwnerPartId=1|LineWidth=1|Color=16711680|LocationCount=4|X1=1205|Y1=760|X2=1205|Y2=740|X3=1225|Y3=750|X4=1205|Y4=760
|RECORD=12|OwnerIndex=434|IsNotAccesible=T|IndexInSheet=18|OwnerPartId=1|Location.X=1215|Location.Y=757|Radius=1|Radius_Frac=79777|LineWidth=1|EndAngle=360.000|Color=16711680
|RECORD=6|OwnerIndex=434|IsNotAccesible=T|IndexInSheet=19|OwnerPartId=1|LineWidth=1|Color=16711680|LocationCount=4|X1=1225|Y1=705|X2=1225|Y2=685|X3=1205|Y3=695|X4=1225|Y4=705
|RECORD=12|OwnerIndex=434|IsNotAccesible=T|IndexInSheet=20|OwnerPartId=1|Location.X=1215|Location.Y=702|Radius=1|Radius_Frac=79777|LineWidth=1|EndAngle=360.000|Color=16711680
|RECORD=6|OwnerIndex=434|IsNotAccesible=T|IndexInSheet=21|OwnerPartId=1|LineWidth=1|Color=16711680|LocationCount=3|X1=1215|Y1=704|X2=1215|Y2=720|X3=1180|Y3=720
|RECORD=6|OwnerIndex=434|IsNotAccesible=T|IndexInSheet=22|OwnerPartId=1|LineWidth=1|Color=16711680|LocationCount=3|X1=1215|Y1=759|X2=1215|Y2=775|X3=1180|Y3=775
|RECORD=6|OwnerIndex=434|IsNotAccesible=T|IndexInSheet=23|OwnerPartId=1|LineWidth=1|Color=16711680|LocationCount=2|X1=1180|Y1=750|X2=1205|Y2=750
|RECORD=6|OwnerIndex=434|IsNotAccesible=T|IndexInSheet=24|OwnerPartId=1|LineWidth=1|Color=16711680|LocationCount=2|X1=1225|Y1=750|X2=1250|Y2=750
|RECORD=6|OwnerIndex=434|IsNotAccesible=T|IndexInSheet=25|OwnerPartId=1|LineWidth=1|Color=16711680|LocationCount=2|X1=1225|Y1=695|X2=1250|Y2=695
|RECORD=6|OwnerIndex=434|IsNotAccesible=T|IndexInSheet=26|OwnerPartId=1|LineWidth=1|Color=16711680|LocationCount=2|X1=1205|Y1=695|X2=1180|Y2=695
|RECORD=34|OwnerIndex=434|IndexInSheet=-1|OwnerPartId=-1|Location.X=1179|Location.Y=785|Color=8388608|FontID=1|Text=U11|Name=Designator|ReadOnlyState=1
|RECORD=41|OwnerIndex=434|IndexInSheet=-1|OwnerPartId=-1|Location.X=1179|Location.Y=650|Color=8388608|FontID=1|Text=NC7WV125K8X|Name=Comment
|RECORD=44|OwnerIndex=434
|RECORD=45|OwnerIndex=472|IndexInSheet=-1|ModelName=SOP50P310X90-8N|ModelType=PCBLIB|DatafileCount=1|ModelDatafile0=C:\Users\<user>\Documents\AltiumLL\SamacSys.PcbLib|ModelDatafileEntity0=SOP50P310X90-8N|ModelDatafileKind0=PCBLIB|IsCurrent=T
|RECORD=46|OwnerIndex=473
|RECORD=48|OwnerIndex=473
|RECORD=17|IndexInSheet=52|OwnerPartId=-1|Style=4|ShowNetName=T|Location.X=1470|Location.Y=620|Orientation=3|Color=128|FontID=1|Text=GND
|RECORD=1|LibReference=CN-1P-M-RF3|ComponentDescription=Ultra Miniature Coaxial Connector Jack, 60 V, 50 Ohm, -40 to 90 degC, RoHS, Tape and Reel|PartCount=2|DisplayModeCount=1|IndexInSheet=53|OwnerPartId=-1|Location.X=1400|Location.Y=770|CurrentPartId=1|LibraryPath=*|SourceLibraryName=Altium Content Vault|TargetFileName=*|AreaColor=11599871|Color=128|PartIDLocked=T|DesignItemId=CMP-2000-07505-1|AllPinCount=3
|RECORD=8|OwnerIndex=477|IsNotAccesible=T|OwnerPartId=1|Location.X=1420|Location.Y=750|Radius=20|SecondaryRadius=20|LineWidth=1|Color=16711680|AreaColor=16777215
|RECORD=8|OwnerIndex=477|IsNotAccesible=T|IndexInSheet=1|OwnerPartId=1|Location.X=1420|Location.Y=750|Radius=4|SecondaryRadius=4|LineWidth=1|Color=16711680|AreaColor=16777215
|RECORD=2|OwnerIndex=477|OwnerPartId=1|FormalType=1|Electrical=4|PinConglomerate=51|PinLength=10|Location.X=1410|Location.Y=730|Name=1|Designator=1|PinPropagationDelay=0.000000E+000
|RECORD=2|OwnerIndex=477|OwnerPartId=1|FormalType=1|Electrical=4|PinConglomerate=50|PinLength=10|Location.X=1400|Location.Y=750|Name=2|Designator=2|PinPropagationDelay=0.000000E+000
|RECORD=2|OwnerIndex=477|OwnerPartId=1|FormalType=1|Electrical=4|PinConglomerate=51|PinLength=10|Location.X=1430|Location.Y=730|Name=3|Designator=3|PinPropagationDelay=0.000000E+000
|RECORD=6|OwnerIndex=477|IsNotAccesible=T|IndexInSheet=5|OwnerPartId=1|LineWidth=1|Color=16711680|LocationCount=5|X1=1400|Y1=730|X2=1400|Y2=770|X3=1440|Y3=770|X4=1440|Y4=730|X5=1400|Y5=730
|RECORD=6|OwnerIndex=477|IsNotAccesible=T|IndexInSheet=6|OwnerPartId=1|LineWidth=1|Color=16711680|LocationCount=2|X1=1400|Y1=750|X2=1416|Y2=750
|RECORD=41|OwnerIndex=477|IndexInSheet=7|OwnerPartId=-1|Location.X=1388|Location.Y=771|Color=8388608|FontID=1|IsHidden=T|Text=Straight|Name=Orientation
|RECORD=41|OwnerIndex=477|IndexInSheet=8|OwnerPartId=-1|Location.X=1388|Location.Y=771|Color=8388608|FontID=1|IsHidden=T|Text=Female|Name=Gender
|RECORD=41|OwnerIndex=477|IndexInSheet=9|OwnerPartId=-1|Location.X=1388|Location.Y=771|Color=8388608|FontID=1|IsHidden=T|Text=Vertical|Name=PCB Mounting Orientation
|RECORD=41|OwnerIndex=477|IndexInSheet=10|OwnerPartId=-1|Location.X=1388|Location.Y=771|Color=8388608|FontID=1|IsHidden=T|Text=SurfaceMount|Name=Mount
|RECORD=41|OwnerIndex=477|IndexInSheet=11|OwnerPartId=-1|Location.X=1388|Location.Y=771|Color=8388608|FontID=1|IsHidden=T|Text=3mm|Name=Length
|RECORD=41|OwnerIndex=477|IndexInSheet=12|OwnerPartId=-1|Location.X=1388|Location.Y=771|Color=8388608|FontID=1|IsHidden=T|Text=TapeandReel|Name=Packaging
|RECORD=41|OwnerIndex=477|IndexInSheet=13|OwnerPartId=-1|Location.X=1388|Location.Y=771|Color=8388608|FontID=1|IsHidden=T|Text=Jack|Name=Connector Type
|RECORD=41|OwnerIndex=477|IndexInSheet=14|OwnerPartId=-1|Location.X=1388|Location.Y=771|Color=8388608|FontID=1|IsHidden=T|Text=LeadFree|Name=Lead Free
|RECORD=41|OwnerIndex=477|IndexInSheet=15|OwnerPartId=-1|Location.X=1388|Location.Y=771|Color=8388608|FontID=1|IsHidden=T|Text=1|Name=Package Quantity
|RECORD=41|OwnerIndex=477|IndexInSheet=16|OwnerPartId=-1|Location.X=1388|Location.Y=771|Color=8388608|FontID=1|IsHidden=T|Text=SMD/SMT|Name=Termination
|RECORD=41|OwnerIndex=477|IndexInSheet=17|OwnerPartId=-1|Location.X=1388|Location.Y=771|Color=8388608|FontID=1|IsHidden=T|Text=CopperAlloy|Name=Contact Material
|RECORD=41|OwnerIndex=477|IndexInSheet=18|OwnerPartId=-1|Location.X=1388|Location.Y=771|Color=8388608|FontID=1|IsHidden=T|Text=Pull|Name=Fastening Type
|RECORD=41|OwnerIndex=477|IndexInSheet=19|OwnerPartId=-1|Location.X=1388|Location.Y=771|Color=8388608|FontID=1|IsHidden=T|Text=true|Name=RoHSCompliant
|RECORD=41|OwnerIndex=477|IndexInSheet=20|OwnerPartId=-1|Location.X=1388|Location.Y=771|Color=8388608|FontID=1|IsHidden=T|Text=LiquidCrystalPolymer|Name=Body Material
|RECORD=41|OwnerIndex=477|IndexInSheet=21|OwnerPartId=-1|Location.X=1388|Location.Y=771|Color=8388608|FontID=1|IsHidden=T|Text=SMD/SMT|Name=Case\/Package
|RECORD=41|OwnerIndex=477|IndexInSheet=22|OwnerPartId=-1|Location.X=1388|Location.Y=771|Color=8388608|FontID=1|IsHidden=T|Text=90degC|Name=Max Operating Temperature
|RECORD=41|OwnerIndex=477|IndexInSheet=23|OwnerPartId=-1|Location.X=1388|Location.Y=771|Color=8388608|FontID=1|IsHidden=T|Text=50Ohm|Name=Impedance
|RECORD=41|OwnerIndex=477|IndexInSheet=24|OwnerPartId=-1|Location.X=1388|Location.Y=771|Color=8388608|FontID=6|IsHidden=T|Text=http://www.te.com/commerce/DocumentDelivery/DDEController?Action=srchrtrv&DocNm=1909763&DocType=Customer+Drawing&DocLang=English|Name=Datasheet URL
|RECORD=41|OwnerIndex=477|IndexInSheet=25|OwnerPartId=-1|Location.X=1388|Location.Y=771|Color=8388608|FontID=1|IsHidden=T|Text=Gold|Name=Contact Plating
|RECORD=41|OwnerIndex=477|IndexInSheet=26|OwnerPartId=-1|Location.X=1388|Location.Y=771|Color=8388608|FontID=1|IsHidden=T|Text=SurfaceMount|Name=Mounting Technology
|RECORD=41|OwnerIndex=477|IndexInSheet=27|OwnerPartId=-1|Location.X=1388|Location.Y=771|Color=8388608|FontID=1|IsHidden=T|Text=6GHz|Name=Max Frequency
|RECORD=41|OwnerIndex=477|IndexInSheet=28|OwnerPartId=-1|Location.X=1388|Location.Y=771|Color=8388608|FontID=1|IsHidden=T|Text=TECO-1909763-1|Name=Package Reference
|RECORD=41|OwnerIndex=477|IndexInSheet=29|OwnerPartId=-1|Location.X=1388|Location.Y=771|Color=8388608|FontID=1|IsHidden=T|Text=Thermoplastic|Name=Insulation Material
|RECORD=41|OwnerIndex=477|IndexInSheet=30|OwnerPartId=-1|Location.X=1388|Location.Y=771|Color=8388608|FontID=1|IsHidden=T|Text=-40degC|Name=Min Operating Temperature
|RECORD=41|OwnerIndex=477|IndexInSheet=31|OwnerPartId=-1|Location.X=1388|Location.Y=771|Color=8388608|FontID=6|IsHidden=T|Text=http://www.te.com/|Name=Manufacturer URL
|RECORD=41|OwnerIndex=477|IndexInSheet=32|OwnerPartId=-1|Location.X=1388|Location.Y=771|Color=8388608|FontID=1|IsHidden=T|Text=Gold|Name=Body Plating
|RECORD=41|OwnerIndex=477|IndexInSheet=33|OwnerPartId=-1|Location.X=1388|Location.Y=771|Color=8388608|FontID=1|IsHidden=T|Text=Polymer|Name=Dielectric Material
|RECORD=41|OwnerIndex=477|IndexInSheet=34|OwnerPartId=-1|Location.X=1388|Location.Y=771|Color=8388608|FontID=1|IsHidden=T|Text=TE Connectivity|Name=Manufacturer
|RECORD=41|OwnerIndex=477|IndexInSheet=35|OwnerPartId=-1|Location.X=1388|Location.Y=771|Color=8388608|FontID=1|IsHidden=T|Text=Compliant|Name=ELV
|RECORD=41|OwnerIndex=477|IndexInSheet=36|OwnerPartId=-1|Location.X=1388|Location.Y=771|Color=8388608|FontID=1|IsHidden=T|Text=Rev. B2, 11/2015|Name=Datasheet Version
|RECORD=41|OwnerIndex=477|IndexInSheet=37|OwnerPartId=-1|Location.X=1388|Location.Y=771|Color=8388608|FontID=1|IsHidden=T|Text=No|Name=Radiation Hardening
|RECORD=41|OwnerIndex=477|IndexInSheet=38|OwnerPartId=-1|Location.X=1388|Location.Y=771|Color=8388608|FontID=1|IsHidden=T|Text=3-Pin Surface Mount Device, Body 2.6 x 2.6 mm|Name=Package Description
|RECORD=41|OwnerIndex=477|IndexInSheet=39|OwnerPartId=-1|Location.X=1388|Location.Y=771|Color=8388608|FontID=1|IsHidden=T|Text=Beige|Name=Housing Colour
|RECORD=34|OwnerIndex=477|IndexInSheet=-1|OwnerPartId=-1|Location.X=1399|Location.Y=771|Color=8388608|FontID=1|Text=J3|Name=Designator|ReadOnlyState=1
|RECORD=41|OwnerIndex=477|IndexInSheet=-1|OwnerPartId=-1|Location.X=1450|Location.Y=730|Color=8388608|FontID=1|Text=1909763-1|Name=Comment
|RECORD=44|OwnerIndex=477
|RECORD=45|OwnerIndex=523|IndexInSheet=-1|Description=SMD, 3-Leads, Body 2.6x2.6mm, Height 1.25mm|UseComponentLibrary=T|ModelName=TECO-1909763-1_V|ModelType=PCBLIB|DatafileCount=1|ModelDatafileEntity0=TECO-1909763-1_V|ModelDatafileKind0=PCBLib|IsCurrent=T|DatalinksLocked=T|DatabaseDatalinksLocked=T
|RECORD=46|OwnerIndex=524
|RECORD=48|OwnerIndex=524
|RECORD=41|OwnerIndex=526|IndexInSheet=-1|OwnerPartId=-1|Color=8388608|FontID=1|Text=2D|Name=Available Preview Images
|RECORD=1|LibReference=CN-S-4F-RF5|ComponentDescription=Coaxial connector, 50 Ohm, -65 to 165 degC, 5-Pin THD, RoHS, Bulk|PartCount=2|DisplayModeCount=1|IndexInSheet=54|OwnerPartId=-1|Location.X=1400|Location.Y=690|CurrentPartId=1|LibraryPath=*|SourceLibraryName=Altium Content Vault|TargetFileName=*|AreaColor=11599871|Color=128|PartIDLocked=T|DesignItemId=CMP-2000-05705-1|AllPinCount=5
|RECORD=2|OwnerIndex=528|OwnerPartId=1|FormalType=1|Electrical=4|PinConglomerate=51|PinLength=10|Location.X=1440|Location.Y=650|Name=5|Designator=5|SwapIDPart=Ž&Ž1|PinPropagationDelay=0.000000E+000
|RECORD=8|OwnerIndex=528|IsNotAccesible=T|IndexInSheet=1|OwnerPartId=1|Location.X=1420|Location.Y=670|Radius=20|SecondaryRadius=20|LineWidth=1|Color=16711680|AreaColor=16777215
|RECORD=8|OwnerIndex=528|IsNotAccesible=T|IndexInSheet=2|OwnerPartId=1|Location.X=1420|Location.Y=670|Radius=4|SecondaryRadius=4|LineWidth=1|Color=16711680|AreaColor=16777215
|RECORD=2|OwnerIndex=528|OwnerPartId=1|FormalType=1|Electrical=4|PinConglomerate=50|PinLength=10|Location.X=1400|Location.Y=670|Name=1|Designator=1|PinPropagationDelay=0.000000E+000
|RECORD=2|OwnerIndex=528|OwnerPartId=1|FormalType=1|Electrical=4|PinConglomerate=51|PinLength=10|Location.X=1410|Location.Y=650|Name=2|Designator=2|PinPropagationDelay=0.000000E+000
|RECORD=2|OwnerIndex=528|OwnerPartId=1|FormalType=1|Electrical=4|PinConglomerate=51|PinLength=10|Location.X=1420|Location.Y=650|Name=3|Designator=3|PinPropagationDelay=0.000000E+000
|RECORD=2|OwnerIndex=528|OwnerPartId=1|FormalType=1|Electrical=4|PinConglomerate=51|PinLength=10|Location.X=1430|Location.Y=650|Name=4|Designator=4|PinPropagationDelay=0.000000E+000
|RECORD=6|OwnerIndex=528|IsNotAccesible=T|IndexInSheet=7|OwnerPartId=1|LineWidth=1|Color=16711680|LocationCount=5|X1=1400|Y1=650|X2=1400|Y2=690|X3=1440|Y3=690|X4=1440|Y4=650|X5=1400|Y5=650
|RECORD=6|OwnerIndex=528|IsNotAccesible=T|IndexInSheet=8|OwnerPartId=1|LineWidth=1|Color=16711680|LocationCount=2|X1=1400|Y1=670|X2=1416|Y2=670
|RECORD=41|OwnerIndex=528|IndexInSheet=9|OwnerPartId=-1|Location.X=1388|Location.Y=691|Color=8388608|FontID=1|IsHidden=T|Text=ThroughHole|Name=Mounting Technology
|RECORD=41|OwnerIndex=528|IndexInSheet=10|OwnerPartId=-1|Location.X=1388|Location.Y=691|Color=8388608|FontID=1|IsHidden=T|Text=ThroughHole,RightAngle|Name=Mounting Type
|RECORD=41|OwnerIndex=528|IndexInSheet=11|OwnerPartId=-1|Location.X=1388|Location.Y=691|Color=8388608|FontID=1|IsHidden=T|Text=-|Name=Cable Group
|RECORD=41|OwnerIndex=528|IndexInSheet=12|OwnerPartId=-1|Location.X=1388|Location.Y=691|Color=8388608|FontID=1|IsHidden=T|Text=901-143-6RFXMountingHole|Name=Catalog Drawings
|RECORD=41|OwnerIndex=528|IndexInSheet=13|OwnerPartId=-1|Location.X=1388|Location.Y=691|Color=8388608|FontID=1|IsHidden=T|Text=901-143-6RFX.igs|Name=3D Model
|RECORD=41|OwnerIndex=528|IndexInSheet=14|OwnerPartId=-1|Location.X=1388|Location.Y=691|Color=8388608|FontID=1|IsHidden=T|Text=-|Name=Series
|RECORD=41|OwnerIndex=528|IndexInSheet=15|OwnerPartId=-1|Location.X=1388|Location.Y=691|Color=8388608|FontID=1|IsHidden=T|Text=5-Pin Through Hole Device, Body 7 x 7 mm, Pitch 2.54 mm|Name=Package Description
|RECORD=41|OwnerIndex=528|IndexInSheet=16|OwnerPartId=-1|Location.X=1388|Location.Y=691|Color=8388608|FontID=1|IsHidden=T|Text=901-143-6RFX|Name=Package Reference
|RECORD=41|OwnerIndex=528|IndexInSheet=17|OwnerPartId=-1|Location.X=1388|Location.Y=691|Color=8388608|FontID=1|IsHidden=T|Text=Brass|Name=Body Material
|RECORD=41|OwnerIndex=528|IndexInSheet=18|OwnerPartId=-1|Location.X=1388|Location.Y=691|Color=8388608|FontID=1|IsHidden=T|Text=-|Name=Voltage Rating
|RECORD=41|OwnerIndex=528|IndexInSheet=19|OwnerPartId=-1|Location.X=1388|Location.Y=691|Color=8388608|FontID=1|IsHidden=T|Text=1|Name=Standard Package
|RECORD=41|OwnerIndex=528|IndexInSheet=20|OwnerPartId=-1|Location.X=1388|Location.Y=691|Color=8388608|FontID=1|IsHidden=T|Text=Jack,FemaleSocket|Name=Connector Type
|RECORD=41|OwnerIndex=528|IndexInSheet=21|OwnerPartId=-1|Location.X=1388|Location.Y=691|Color=8388608|FontID=1|IsHidden=T|Text=Threaded|Name=Fastening Type
|RECORD=41|OwnerIndex=528|IndexInSheet=22|OwnerPartId=-1|Location.X=1388|Location.Y=691|Color=8388608|FontID=1|IsHidden=T|Text=Gold|Name=Housing Color
|RECORD=41|OwnerIndex=528|IndexInSheet=23|OwnerPartId=-1|Location.X=1388|Location.Y=691|Color=8388608|FontID=1|IsHidden=T|Text=Solder|Name=Shield Termination
|RECORD=41|OwnerIndex=528|IndexInSheet=24|OwnerPartId=-1|Location.X=1388|Location.Y=691|Color=8388608|FontID=1|IsHidden=T|Text=901-143-6-RFX9011436RFXARFX1232|Name=Other Names
|RECORD=41|OwnerIndex=528|IndexInSheet=25|OwnerPartId=-1|Location.X=1388|Location.Y=691|Color=8388608|FontID=6|IsHidden=T|Text=http://www.amphenolrf.com/downloads/dl/file/id/2712/product/3102/901_143_6rfx_customer_drawing.pdf|Name=Datasheet URL
|RECORD=41|OwnerIndex=528|IndexInSheet=26|OwnerPartId=-1|Location.X=1388|Location.Y=691|Color=8388608|FontID=1|IsHidden=T|Text=CoaxialConnectors(RF)|Name=Family
|RECORD=41|OwnerIndex=528|IndexInSheet=27|OwnerPartId=-1|Location.X=1388|Location.Y=691|Color=8388608|FontID=1|IsHidden=T|Text=SMA,RFX|Name=Online Catalog
|RECORD=41|OwnerIndex=528|IndexInSheet=28|OwnerPartId=-1|Location.X=1388|Location.Y=691|Color=8388608|FontID=1|IsHidden=T|Text=18GHz|Name=Frequency - Max
|RECORD=41|OwnerIndex=528|IndexInSheet=29|OwnerPartId=-1|Location.X=1388|Location.Y=691|Color=8388608|FontID=1|IsHidden=T|Text=Solder|Name=Contact Termination
|RECORD=41|OwnerIndex=528|IndexInSheet=30|OwnerPartId=-1|Location.X=1388|Location.Y=691|Color=8388608|FontID=6|IsHidden=T|Text=http://www.amphenol.com/|Name=Manufacturer URL
|RECORD=41|OwnerIndex=528|IndexInSheet=31|OwnerPartId=-1|Location.X=1388|Location.Y=691|Color=8388608|FontID=1|IsHidden=T|Text=Amphenol|Name=Manufacturer
|RECORD=41|OwnerIndex=528|IndexInSheet=32|OwnerPartId=-1|Location.X=1388|Location.Y=691|Color=8388608|FontID=1|IsHidden=T|Text=-65°C~165°C|Name=Operating Temperature
|RECORD=41|OwnerIndex=528|IndexInSheet=33|OwnerPartId=-1|Location.X=1388|Location.Y=691|Color=8388608|FontID=1|IsHidden=T|Text=Connectors,Interconnects|Name=Category
|RECORD=41|OwnerIndex=528|IndexInSheet=34|OwnerPartId=-1|Location.X=1388|Location.Y=691|Color=8388608|FontID=1|IsHidden=T|Text=Bulk|Name=Packaging
|RECORD=41|OwnerIndex=528|IndexInSheet=35|OwnerPartId=-1|Location.X=1388|Location.Y=691|Color=8388608|FontID=1|IsHidden=T|Text=Gold|Name=Body Finish
|RECORD=41|OwnerIndex=528|IndexInSheet=36|OwnerPartId=-1|Location.X=1388|Location.Y=691|Color=8388608|FontID=1|IsHidden=T|Text=Polytetrafluoroethylene(PTFE)|Name=Dielectric Material
|RECORD=41|OwnerIndex=528|IndexInSheet=37|OwnerPartId=-1|Location.X=1388|Location.Y=691|Color=8388608|FontID=1|IsHidden=T|Text=BerylliumCopper|Name=Center Contact Material
|RECORD=41|OwnerIndex=528|IndexInSheet=38|OwnerPartId=-1|Location.X=1388|Location.Y=691|Color=8388608|FontID=1|IsHidden=T|Text=50Ohm|Name=Impedance
|RECORD=41|OwnerIndex=528|IndexInSheet=39|OwnerPartId=-1|Location.X=1388|Location.Y=691|Color=8388608|FontID=1|IsHidden=T|Text=-|Name=Features
|RECORD=41|OwnerIndex=528|IndexInSheet=40|OwnerPartId=-1|Location.X=1388|Location.Y=691|Color=8388608|FontID=1|IsHidden=T|Text=SMA|Name=Connector Style
|RECORD=41|OwnerIndex=528|IndexInSheet=41|OwnerPartId=-1|Location.X=1388|Location.Y=691|Color=8388608|FontID=1|IsHidden=T|Text=Gold|Name=Center Contact Plating
|RECORD=41|OwnerIndex=528|IndexInSheet=42|OwnerPartId=-1|Location.X=1388|Location.Y=691|Color=8388608|FontID=1|IsHidden=T|Text=Rev. C, 06/2010|Name=Datasheet Version
|RECORD=41|OwnerIndex=528|IndexInSheet=43|OwnerPartId=-1|Location.X=1388|Location.Y=691|Color=8388608|FontID=1|IsHidden=T|Text=-|Name=Ingress Protection
|RECORD=34|OwnerIndex=528|IndexInSheet=-1|OwnerPartId=-1|Location.X=1399|Location.Y=691|Color=8388608|FontID=1|Text=AN3|Name=Designator|ReadOnlyState=1
|RECORD=41|OwnerIndex=528|IndexInSheet=-1|OwnerPartId=-1|Location.X=1450|Location.Y=640|Color=8388608|FontID=1|Text=901-143-6RFX|Name=Comment
|RECORD=44|OwnerIndex=528
|RECORD=45|OwnerIndex=580|IndexInSheet=-1|Description=THD, 5-Leads, Body 7x7mm, Pitch 2.54mm|UseComponentLibrary=T|ModelName=AMPH-901-143-6RFX_V|ModelType=PCBLIB|DatafileCount=1|ModelDatafileEntity0=AMPH-901-143-6RFX_V|ModelDatafileKind0=PCBLib|IsCurrent=T|DatalinksLocked=T|DatabaseDatalinksLocked=T
|RECORD=46|OwnerIndex=581
|RECORD=48|OwnerIndex=581
|RECORD=41|OwnerIndex=583|IndexInSheet=-1|OwnerPartId=-1|Color=8388608|FontID=1|Text=2D|Name=Available Preview Images
|RECORD=17|IndexInSheet=55|OwnerPartId=-1|Style=4|ShowNetName=T|Location.X=1470|Location.Y=710|Orientation=3|Color=128|FontID=1|Text=GND
|RECORD=1|LibReference=RES-2|ComponentDescription=General Purpose Chip Resistor, 49.9 Ohm, +/- 1%, -55 to 155 degC, 0603 (1608 Metric), RoHS, Tape and Reel|PartCount=2|DisplayModeCount=1|IndexInSheet=56|OwnerPartId=-1|Location.X=1305|Location.Y=750|CurrentPartId=1|LibraryPath=*|SourceLibraryName=Altium Content Vault|TargetFileName=*|AreaColor=11599871|Color=128|PartIDLocked=T|DesignItemId=CMP-1659-00036-1|AllPinCount=2
|RECORD=2|OwnerIndex=586|OwnerPartId=1|FormalType=1|Electrical=4|PinConglomerate=32|PinLength=10|Location.X=1325|Location.Y=750|Name=2|Designator=2|PinPropagationDelay=0.000000E+000
|RECORD=2|OwnerIndex=586|OwnerPartId=1|FormalType=1|Electrical=4|PinConglomerate=34|PinLength=10|Location.X=1305|Location.Y=750|Name=1|Designator=1|PinPropagationDelay=0.000000E+000
|RECORD=6|OwnerIndex=586|IsNotAccesible=T|IndexInSheet=2|OwnerPartId=1|LineWidth=1|Color=16711680|LocationCount=10|X1=1325|Y1=750|X2=1321|Y2=750|X3=1320|Y3=748|X4=1318|Y4=752|X5=1316|Y5=748|X6=1314|Y6=752|X7=1312|Y7=748|X8=1310|Y8=752|X9=1309|Y9=750|X10=1305|Y10=750
|RECORD=41|OwnerIndex=586|IndexInSheet=3|OwnerPartId=-1|Location.X=1293|Location.Y=765|Color=8388608|FontID=1|IsHidden=T|Text=0603|Name=PackageReference
|RECORD=41|OwnerIndex=586|IndexInSheet=4|OwnerPartId=-1|Location.X=1293|Location.Y=765|Color=8388608|FontID=1|IsHidden=T|Text=Tray|Name=Packaging
|RECORD=41|OwnerIndex=586|IndexInSheet=5|OwnerPartId=-1|Location.X=1293|Location.Y=765|Color=8388608|FontID=1|IsHidden=T|Text=Datasheet|Name=ComponentLink2Description
|RECORD=41|OwnerIndex=586|IndexInSheet=6|OwnerPartId=-1|Location.X=1293|Location.Y=765|Color=8388608|FontID=1|IsHidden=T|Text=Manufacturer URL|Name=ComponentLink1Description
|RECORD=41|OwnerIndex=586|IndexInSheet=7|OwnerPartId=-1|Location.X=1293|Location.Y=765|Color=8388608|FontID=6|IsHidden=T|Text=https://datasheet.ciiva.com/11808/0900766b80f96399-11808223.pdf|Name=ComponentLink2URL
|RECORD=41|OwnerIndex=586|IndexInSheet=8|OwnerPartId=-1|Location.X=1293|Location.Y=765|Color=8388608|FontID=1|IsHidden=T|Text=true|Name=RoHSCompliant
|RECORD=41|OwnerIndex=586|IndexInSheet=9|OwnerPartId=-1|Location.X=1293|Location.Y=765|Color=8388608|FontID=1|IsHidden=T|Text=85 degC|Name=Max Operating Temperature
|RECORD=41|OwnerIndex=586|IndexInSheet=10|OwnerPartId=-1|Location.X=1293|Location.Y=765|Color=8388608|FontID=1|IsHidden=T|Text=3.63 V|Name=Max Supply Voltage
|RECORD=41|OwnerIndex=586|IndexInSheet=11|OwnerPartId=-1|Location.X=1293|Location.Y=765|Color=8388608|FontID=6|IsHidden=T|Text=http://www.yageo.com/|Name=ComponentLink1URL
|RECORD=41|OwnerIndex=586|IndexInSheet=12|OwnerPartId=-1|Location.X=1293|Location.Y=765|Color=8388608|FontID=1|IsHidden=T|Text=2-Pin Surface Mount Device, Body 1.6 x 0.8 mm|Name=PackageDescription
|RECORD=41|OwnerIndex=586|IndexInSheet=13|OwnerPartId=-1|Location.X=1293|Location.Y=765|Color=8388608|FontID=1|IsHidden=T|Text=LQFP|Name=Case\Package
|RECORD=41|OwnerIndex=586|IndexInSheet=14|OwnerPartId=-1|Location.X=1293|Location.Y=765|Color=8388608|FontID=1|IsHidden=T|Text=Rev. 4, 04/2009|Name=DatasheetVersion
|RECORD=41|OwnerIndex=586|IndexInSheet=15|OwnerPartId=-1|Location.X=1293|Location.Y=765|Color=8388608|FontID=1|IsHidden=T|Text=-40 degC|Name=Min Operating Temperature
|RECORD=41|OwnerIndex=586|IndexInSheet=16|OwnerPartId=-1|Location.X=1293|Location.Y=765|Color=8388608|FontID=1|IsHidden=T|Text=SPI|Name=Interface
|RECORD=41|OwnerIndex=586|IndexInSheet=17|OwnerPartId=-1|Location.X=1293|Location.Y=765|Color=8388608|FontID=1|IsHidden=T|Text=250|Name=Package Quantity
|RECORD=41|OwnerIndex=586|IndexInSheet=18|OwnerPartId=-1|Location.X=1293|Location.Y=765|Color=8388608|FontID=1|IsHidden=T|Text=2.97 V|Name=Min Supply Voltage
|RECORD=41|OwnerIndex=586|IndexInSheet=19|OwnerPartId=-1|Location.X=1293|Location.Y=765|Color=8388608|FontID=1|IsHidden=T|Text=48|Name=Pins
|RECORD=34|OwnerIndex=586|IndexInSheet=-1|OwnerPartId=-1|Location.X=1304|Location.Y=753|Color=8388608|FontID=1|Text=R28|Name=Designator|ReadOnlyState=1
|RECORD=41|OwnerIndex=586|IndexInSheet=-1|OwnerPartId=-1|Location.X=1304|Location.Y=737|Color=8388608|FontID=1|Text=49.9R|Name=Comment
|RECORD=44|OwnerIndex=586
|RECORD=45|OwnerIndex=611|IndexInSheet=-1|Description=Chip Resistor, 2-Leads, Body 1.70x0.90mm, IPC Medium Density|UseComponentLibrary=T|ModelName=RESC1608X55X25NL10T15|ModelType=PCBLIB|DatafileCount=1|ModelDatafileEntity0=RESC1608X55X25NL10T15|ModelDatafileKind0=PCBLib|IsCurrent=T|DatalinksLocked=T|DatabaseDatalinksLocked=T
|RECORD=46|OwnerIndex=612
|RECORD=48|OwnerIndex=612
|RECORD=41|OwnerIndex=614|IndexInSheet=-1|OwnerPartId=-1|Color=8388608|FontID=1|IsHidden=T|Text=2D|Name=Available Preview Images
|RECORD=45|OwnerIndex=611|IndexInSheet=-1|Description=Chip Resistor, 2-Leads, Body 1.70x0.90mm, IPC Low Density|UseComponentLibrary=T|ModelName=RESC1608X55X25ML10T15|ModelType=PCBLIB|DatafileCount=1|ModelDatafileEntity0=RESC1608X55X25ML10T15|ModelDatafileKind0=PCBLib|DatalinksLocked=T|DatabaseDatalinksLocked=T
|RECORD=46|OwnerIndex=616
|RECORD=48|OwnerIndex=616
|RECORD=41|OwnerIndex=618|IndexInSheet=-1|OwnerPartId=-1|Color=8388608|FontID=1|IsHidden=T|Text=2D|Name=Available Preview Images
|RECORD=45|OwnerIndex=611|IndexInSheet=-1|Description=Chip Resistor, 2-Leads, Body 1.70x0.90mm, IPC High Density|UseComponentLibrary=T|ModelName=RESC1608X55X25LL10T15|ModelType=PCBLIB|DatafileCount=1|ModelDatafileEntity0=RESC1608X55X25LL10T15|ModelDatafileKind0=PCBLib|DatalinksLocked=T|DatabaseDatalinksLocked=T
|RECORD=46|OwnerIndex=620
|RECORD=48|OwnerIndex=620
|RECORD=41|OwnerIndex=622|IndexInSheet=-1|OwnerPartId=-1|Color=8388608|FontID=1|IsHidden=T|Text=2D|Name=Available Preview Images
|RECORD=17|IndexInSheet=57|OwnerPartId=-1|ShowNetName=T|Location.X=1030|Location.Y=750|Orientation=2|Color=255|FontID=1|Text=ANT3_OUT|IsCrossSheetConnector=T
|RECORD=1|LibReference=RES-2|ComponentDescription=Precision Thick Film Chip Resistor, 4.7 KOhm, +/- 1%, -55 to 155 degC, 0603 (1608 Metric), RoHS, Tape and Reel ERJ-3EKF4701V|PartCount=2|DisplayModeCount=1|IndexInSheet=58|OwnerPartId=-1|Location.X=1040|Location.Y=810|Orientation=1|CurrentPartId=1|LibraryPath=*|SourceLibraryName=Altium Content Vault|TargetFileName=*|AreaColor=11599871|Color=128|PartIDLocked=T|DesignItemId=CMP-1012-00586-3|AllPinCount=2
|RECORD=2|OwnerIndex=625|OwnerPartId=1|FormalType=1|Electrical=4|PinConglomerate=33|PinLength=10|Location.X=1040|Location.Y=830|Name=2|Designator=2|PinPropagationDelay=0.000000E+000
|RECORD=2|OwnerIndex=625|OwnerPartId=1|FormalType=1|Electrical=4|PinConglomerate=35|PinLength=10|Location.X=1040|Location.Y=810|Name=1|Designator=1|PinPropagationDelay=0.000000E+000
|RECORD=6|OwnerIndex=625|IsNotAccesible=T|IndexInSheet=2|OwnerPartId=1|LineWidth=1|Color=16711680|LocationCount=10|X1=1040|Y1=830|X2=1040|Y2=826|X3=1042|Y3=825|X4=1038|Y4=823|X5=1042|Y5=821|X6=1038|Y6=819|X7=1042|Y7=817|X8=1038|Y8=815|X9=1040|Y9=814|X10=1040|Y10=810
|RECORD=41|OwnerIndex=625|IndexInSheet=3|OwnerPartId=-1|Location.X=1037|Location.Y=842|Color=8388608|FontID=1|IsHidden=T|Text=220 Ohm|Name=Resistance
|RECORD=41|OwnerIndex=625|IndexInSheet=4|OwnerPartId=-1|Location.X=1037|Location.Y=842|Color=8388608|FontID=1|IsHidden=T|Text=0603|Name=PackageReference
|RECORD=41|OwnerIndex=625|IndexInSheet=5|OwnerPartId=-1|Location.X=1037|Location.Y=842|Color=8388608|FontID=1|IsHidden=T|Text=50 V|Name=Voltage Rating
|RECORD=41|OwnerIndex=625|IndexInSheet=6|OwnerPartId=-1|Location.X=1037|Location.Y=842|Color=8388608|FontID=1|IsHidden=T|Text=125 degC|Name=Max Operating Temperature
|RECORD=41|OwnerIndex=625|IndexInSheet=7|OwnerPartId=-1|Location.X=1037|Location.Y=842|Color=8388608|FontID=1|IsHidden=T|Text=4|Name=Elements
|RECORD=41|OwnerIndex=625|IndexInSheet=8|OwnerPartId=-1|Location.X=1037|Location.Y=842|Color=8388608|FontID=1|IsHidden=T|Text=No SVHC|Name=REACH SVHC
|RECORD=41|OwnerIndex=625|IndexInSheet=9|OwnerPartId=-1|Location.X=1037|Location.Y=842|Color=8388608|FontID=1|IsHidden=T|Text=0.063 inch|Name=Width
|RECORD=41|OwnerIndex=625|IndexInSheet=10|OwnerPartId=-1|Location.X=1037|Location.Y=842|Color=8388608|FontID=1|IsHidden=T|Text=1205|Name=Case\Package
|RECORD=41|OwnerIndex=625|IndexInSheet=11|OwnerPartId=-1|Location.X=1037|Location.Y=842|Color=8388608|FontID=1|IsHidden=T|Text=0.126 inch|Name=Length
|RECORD=41|OwnerIndex=625|IndexInSheet=12|OwnerPartId=-1|Location.X=1037|Location.Y=842|Color=8388608|FontID=1|IsHidden=T|Text=0.024 inch|Name=Height
|RECORD=41|OwnerIndex=625|IndexInSheet=13|OwnerPartId=-1|Location.X=1037|Location.Y=842|Color=8388608|FontID=1|IsHidden=T|Text=Surface Mount|Name=Mount
|RECORD=41|OwnerIndex=625|IndexInSheet=14|OwnerPartId=-1|Location.X=1037|Location.Y=842|Color=8388608|FontID=1|IsHidden=T|Text=1|Name=Package Quantity
|RECORD=41|OwnerIndex=625|IndexInSheet=15|OwnerPartId=-1|Location.X=1037|Location.Y=842|Color=8388608|FontID=1|IsHidden=T|Text=Apr-15|Name=DatasheetVersion
|RECORD=41|OwnerIndex=625|IndexInSheet=16|OwnerPartId=-1|Location.X=1037|Location.Y=842|Color=8388608|FontID=1|IsHidden=T|Text=Manufacturer URL|Name=ComponentLink1Description
|RECORD=41|OwnerIndex=625|IndexInSheet=17|OwnerPartId=-1|Location.X=1037|Location.Y=842|Color=8388608|FontID=1|IsHidden=T|Text=-55 degC|Name=Min Operating Temperature
|RECORD=41|OwnerIndex=625|IndexInSheet=18|OwnerPartId=-1|Location.X=1037|Location.Y=842|Color=8388608|FontID=1|IsHidden=T|Text=Tape and Reel|Name=Packaging
|RECORD=41|OwnerIndex=625|IndexInSheet=19|OwnerPartId=-1|Location.X=1037|Location.Y=842|Color=8388608|FontID=1|IsHidden=T|Text=No|Name=Radiation Hardening
|RECORD=41|OwnerIndex=625|IndexInSheet=20|OwnerPartId=-1|Location.X=1037|Location.Y=842|Color=8388608|FontID=6|IsHidden=T|Text=http://industrial.panasonic.com/cdbs/www-data/pdf/RDA0000/AOA0000C86.pdf|Name=ComponentLink2URL
|RECORD=41|OwnerIndex=625|IndexInSheet=21|OwnerPartId=-1|Location.X=1037|Location.Y=842|Color=8388608|FontID=1|IsHidden=T|Text=3216|Name=Case Code (Metric)
|RECORD=41|OwnerIndex=625|IndexInSheet=22|OwnerPartId=-1|Location.X=1037|Location.Y=842|Color=8388608|FontID=1|IsHidden=T|Text=8|Name=Pins
|RECORD=41|OwnerIndex=625|IndexInSheet=23|OwnerPartId=-1|Location.X=1037|Location.Y=842|Color=8388608|FontID=1|IsHidden=T|Text=1206|Name=Case Code (Imperial)
|RECORD=41|OwnerIndex=625|IndexInSheet=24|OwnerPartId=-1|Location.X=1037|Location.Y=842|Color=8388608|FontID=1|IsHidden=T|Text=Thick Film|Name=Type (Resistor)
|RECORD=41|OwnerIndex=625|IndexInSheet=25|OwnerPartId=-1|Location.X=1037|Location.Y=842|Color=8388608|FontID=1|IsHidden=T|Text=true|Name=RoHSCompliant
|RECORD=41|OwnerIndex=625|IndexInSheet=26|OwnerPartId=-1|Location.X=1037|Location.Y=842|Color=8388608|FontID=1|IsHidden=T|Text=5%|Name=Tolerance
|RECORD=41|OwnerIndex=625|IndexInSheet=27|OwnerPartId=-1|Location.X=1037|Location.Y=842|Color=8388608|FontID=1|IsHidden=T|Text=Datasheet|Name=ComponentLink2Description
|RECORD=41|OwnerIndex=625|IndexInSheet=28|OwnerPartId=-1|Location.X=1037|Location.Y=842|Color=8388608|FontID=1|IsHidden=T|Text=2-Pin Surface Mount Device, Body 1.6 x 0.85 mm|Name=PackageDescription
|RECORD=41|OwnerIndex=625|IndexInSheet=29|OwnerPartId=-1|Location.X=1037|Location.Y=842|Color=8388608|FontID=6|IsHidden=T|Text=http://www.panasonic.com/|Name=ComponentLink1URL
|RECORD=41|OwnerIndex=625|IndexInSheet=30|OwnerPartId=-1|Location.X=1037|Location.Y=842|Color=8388608|FontID=1|IsHidden=T|Text=250 mW|Name=Power Rating
|RECORD=34|OwnerIndex=625|IndexInSheet=-1|OwnerPartId=-1|Location.X=1043|Location.Y=821|Color=8388608|FontID=1|Text=R16|Name=Designator|ReadOnlyState=1
|RECORD=41|OwnerIndex=625|IndexInSheet=-1|OwnerPartId=-1|Location.X=1043|Location.Y=811|Color=8388608|FontID=1|Text=4.7K|Name=Comment
|RECORD=44|OwnerIndex=625
|RECORD=45|OwnerIndex=661|IndexInSheet=-1|Description=Chip Resistor, 2-Leads, Body 1.75x0.95mm, IPC Medium Density|UseComponentLibrary=T|ModelName=RESC1608X55X30NL15T15|ModelType=PCBLIB|DatafileCount=1|ModelDatafileEntity0=RESC1608X55X30NL15T15|ModelDatafileKind0=PCBLib|IsCurrent=T|DatalinksLocked=T|DatabaseDatalinksLocked=T
|RECORD=46|OwnerIndex=662
|RECORD=48|OwnerIndex=662
|RECORD=41|OwnerIndex=664|IndexInSheet=-1|OwnerPartId=-1|Color=8388608|FontID=1|IsHidden=T|Text=2D|Name=Available Preview Images
|RECORD=45|OwnerIndex=661|IndexInSheet=-1|Description=Chip Resistor, 2-Leads, Body 1.75x0.95mm, IPC Low Density|UseComponentLibrary=T|ModelName=RESC1608X55X30ML15T15|ModelType=PCBLIB|DatafileCount=1|ModelDatafileEntity0=RESC1608X55X30ML15T15|ModelDatafileKind0=PCBLib|DatalinksLocked=T|DatabaseDatalinksLocked=T
|RECORD=46|OwnerIndex=666
|RECORD=48|OwnerIndex=666
|RECORD=41|OwnerIndex=668|IndexInSheet=-1|OwnerPartId=-1|Color=8388608|FontID=1|IsHidden=T|Text=2D|Name=Available Preview Images
|RECORD=45|OwnerIndex=661|IndexInSheet=-1|Description=Chip Resistor, 2-Leads, Body 1.75x0.95mm, IPC High Density|UseComponentLibrary=T|ModelName=RESC1608X55X30LL15T15|ModelType=PCBLIB|DatafileCount=1|ModelDatafileEntity0=RESC1608X55X30LL15T15|ModelDatafileKind0=PCBLib|DatalinksLocked=T|DatabaseDatalinksLocked=T
|RECORD=46|OwnerIndex=670
|RECORD=48|OwnerIndex=670
|RECORD=41|OwnerIndex=672|IndexInSheet=-1|OwnerPartId=-1|Color=8388608|FontID=1|IsHidden=T|Text=2D|Name=Available Preview Images
|RECORD=1|LibReference=RES-2|ComponentDescription=Precision Thick Film Chip Resistor, 4.7 KOhm, +/- 1%, -55 to 155 degC, 0603 (1608 Metric), RoHS, Tape and Reel ERJ-3EKF4701V|PartCount=2|DisplayModeCount=1|IndexInSheet=59|OwnerPartId=-1|Location.X=1070|Location.Y=810|Orientation=1|CurrentPartId=1|LibraryPath=*|SourceLibraryName=Altium Content Vault|TargetFileName=*|AreaColor=11599871|Color=128|PartIDLocked=T|DesignItemId=CMP-1012-00586-3|AllPinCount=2
|RECORD=2|OwnerIndex=674|OwnerPartId=1|FormalType=1|Electrical=4|PinConglomerate=33|PinLength=10|Location.X=1070|Location.Y=830|Name=2|Designator=2|PinPropagationDelay=0.000000E+000
|RECORD=2|OwnerIndex=674|OwnerPartId=1|FormalType=1|Electrical=4|PinConglomerate=35|PinLength=10|Location.X=1070|Location.Y=810|Name=1|Designator=1|PinPropagationDelay=0.000000E+000
|RECORD=6|OwnerIndex=674|IsNotAccesible=T|IndexInSheet=2|OwnerPartId=1|LineWidth=1|Color=16711680|LocationCount=10|X1=1070|Y1=830|X2=1070|Y2=826|X3=1072|Y3=825|X4=1068|Y4=823|X5=1072|Y5=821|X6=1068|Y6=819|X7=1072|Y7=817|X8=1068|Y8=815|X9=1070|Y9=814|X10=1070|Y10=810
|RECORD=41|OwnerIndex=674|IndexInSheet=3|OwnerPartId=-1|Location.X=1067|Location.Y=842|Color=8388608|FontID=1|IsHidden=T|Text=220 Ohm|Name=Resistance
|RECORD=41|OwnerIndex=674|IndexInSheet=4|OwnerPartId=-1|Location.X=1067|Location.Y=842|Color=8388608|FontID=1|IsHidden=T|Text=0603|Name=PackageReference
|RECORD=41|OwnerIndex=674|IndexInSheet=5|OwnerPartId=-1|Location.X=1067|Location.Y=842|Color=8388608|FontID=1|IsHidden=T|Text=50 V|Name=Voltage Rating
|RECORD=41|OwnerIndex=674|IndexInSheet=6|OwnerPartId=-1|Location.X=1067|Location.Y=842|Color=8388608|FontID=1|IsHidden=T|Text=125 degC|Name=Max Operating Temperature
|RECORD=41|OwnerIndex=674|IndexInSheet=7|OwnerPartId=-1|Location.X=1067|Location.Y=842|Color=8388608|FontID=1|IsHidden=T|Text=4|Name=Elements
|RECORD=41|OwnerIndex=674|IndexInSheet=8|OwnerPartId=-1|Location.X=1067|Location.Y=842|Color=8388608|FontID=1|IsHidden=T|Text=No SVHC|Name=REACH SVHC
|RECORD=41|OwnerIndex=674|IndexInSheet=9|OwnerPartId=-1|Location.X=1067|Location.Y=842|Color=8388608|FontID=1|IsHidden=T|Text=0.063 inch|Name=Width
|RECORD=41|OwnerIndex=674|IndexInSheet=10|OwnerPartId=-1|Location.X=1067|Location.Y=842|Color=8388608|FontID=1|IsHidden=T|Text=1205|Name=Case\Package
|RECORD=41|OwnerIndex=674|IndexInSheet=11|OwnerPartId=-1|Location.X=1067|Location.Y=842|Color=8388608|FontID=1|IsHidden=T|Text=0.126 inch|Name=Length
|RECORD=41|OwnerIndex=674|IndexInSheet=12|OwnerPartId=-1|Location.X=1067|Location.Y=842|Color=8388608|FontID=1|IsHidden=T|Text=0.024 inch|Name=Height
|RECORD=41|OwnerIndex=674|IndexInSheet=13|OwnerPartId=-1|Location.X=1067|Location.Y=842|Color=8388608|FontID=1|IsHidden=T|Text=Surface Mount|Name=Mount
|RECORD=41|OwnerIndex=674|IndexInSheet=14|OwnerPartId=-1|Location.X=1067|Location.Y=842|Color=8388608|FontID=1|IsHidden=T|Text=1|Name=Package Quantity
|RECORD=41|OwnerIndex=674|IndexInSheet=15|OwnerPartId=-1|Location.X=1067|Location.Y=842|Color=8388608|FontID=1|IsHidden=T|Text=Apr-15|Name=DatasheetVersion
|RECORD=41|OwnerIndex=674|IndexInSheet=16|OwnerPartId=-1|Location.X=1067|Location.Y=842|Color=8388608|FontID=1|IsHidden=T|Text=Manufacturer URL|Name=ComponentLink1Description
|RECORD=41|OwnerIndex=674|IndexInSheet=17|OwnerPartId=-1|Location.X=1067|Location.Y=842|Color=8388608|FontID=1|IsHidden=T|Text=-55 degC|Name=Min Operating Temperature
|RECORD=41|OwnerIndex=674|IndexInSheet=18|OwnerPartId=-1|Location.X=1067|Location.Y=842|Color=8388608|FontID=1|IsHidden=T|Text=Tape and Reel|Name=Packaging
|RECORD=41|OwnerIndex=674|IndexInSheet=19|OwnerPartId=-1|Location.X=1067|Location.Y=842|Color=8388608|FontID=1|IsHidden=T|Text=No|Name=Radiation Hardening
|RECORD=41|OwnerIndex=674|IndexInSheet=20|OwnerPartId=-1|Location.X=1067|Location.Y=842|Color=8388608|FontID=6|IsHidden=T|Text=http://industrial.panasonic.com/cdbs/www-data/pdf/RDA0000/AOA0000C86.pdf|Name=ComponentLink2URL
|RECORD=41|OwnerIndex=674|IndexInSheet=21|OwnerPartId=-1|Location.X=1067|Location.Y=842|Color=8388608|FontID=1|IsHidden=T|Text=3216|Name=Case Code (Metric)
|RECORD=41|OwnerIndex=674|IndexInSheet=22|OwnerPartId=-1|Location.X=1067|Location.Y=842|Color=8388608|FontID=1|IsHidden=T|Text=8|Name=Pins
|RECORD=41|OwnerIndex=674|IndexInSheet=23|OwnerPartId=-1|Location.X=1067|Location.Y=842|Color=8388608|FontID=1|IsHidden=T|Text=1206|Name=Case Code (Imperial)
|RECORD=41|OwnerIndex=674|IndexInSheet=24|OwnerPartId=-1|Location.X=1067|Location.Y=842|Color=8388608|FontID=1|IsHidden=T|Text=Thick Film|Name=Type (Resistor)
|RECORD=41|OwnerIndex=674|IndexInSheet=25|OwnerPartId=-1|Location.X=1067|Location.Y=842|Color=8388608|FontID=1|IsHidden=T|Text=true|Name=RoHSCompliant
|RECORD=41|OwnerIndex=674|IndexInSheet=26|OwnerPartId=-1|Location.X=1067|Location.Y=842|Color=8388608|FontID=1|IsHidden=T|Text=5%|Name=Tolerance
|RECORD=41|OwnerIndex=674|IndexInSheet=27|OwnerPartId=-1|Location.X=1067|Location.Y=842|Color=8388608|FontID=1|IsHidden=T|Text=Datasheet|Name=ComponentLink2Description
|RECORD=41|OwnerIndex=674|IndexInSheet=28|OwnerPartId=-1|Location.X=1067|Location.Y=842|Color=8388608|FontID=1|IsHidden=T|Text=2-Pin Surface Mount Device, Body 1.6 x 0.85 mm|Name=PackageDescription
|RECORD=41|OwnerIndex=674|IndexInSheet=29|OwnerPartId=-1|Location.X=1067|Location.Y=842|Color=8388608|FontID=6|IsHidden=T|Text=http://www.panasonic.com/|Name=ComponentLink1URL
|RECORD=41|OwnerIndex=674|IndexInSheet=30|OwnerPartId=-1|Location.X=1067|Location.Y=842|Color=8388608|FontID=1|IsHidden=T|Text=250 mW|Name=Power Rating
|RECORD=34|OwnerIndex=674|IndexInSheet=-1|OwnerPartId=-1|Location.X=1073|Location.Y=821|Color=8388608|FontID=1|Text=R17|Name=Designator|ReadOnlyState=1
|RECORD=41|OwnerIndex=674|IndexInSheet=-1|OwnerPartId=-1|Location.X=1073|Location.Y=811|Color=8388608|FontID=1|Text=4.7K|Name=Comment
|RECORD=44|OwnerIndex=674
|RECORD=45|OwnerIndex=710|IndexInSheet=-1|Description=Chip Resistor, 2-Leads, Body 1.75x0.95mm, IPC Medium Density|UseComponentLibrary=T|ModelName=RESC1608X55X30NL15T15|ModelType=PCBLIB|DatafileCount=1|ModelDatafileEntity0=RESC1608X55X30NL15T15|ModelDatafileKind0=PCBLib|IsCurrent=T|DatalinksLocked=T|DatabaseDatalinksLocked=T
|RECORD=46|OwnerIndex=711
|RECORD=48|OwnerIndex=711
|RECORD=41|OwnerIndex=713|IndexInSheet=-1|OwnerPartId=-1|Color=8388608|FontID=1|IsHidden=T|Text=2D|Name=Available Preview Images
|RECORD=45|OwnerIndex=710|IndexInSheet=-1|Description=Chip Resistor, 2-Leads, Body 1.75x0.95mm, IPC Low Density|UseComponentLibrary=T|ModelName=RESC1608X55X30ML15T15|ModelType=PCBLIB|DatafileCount=1|ModelDatafileEntity0=RESC1608X55X30ML15T15|ModelDatafileKind0=PCBLib|DatalinksLocked=T|DatabaseDatalinksLocked=T
|RECORD=46|OwnerIndex=715
|RECORD=48|OwnerIndex=715
|RECORD=41|OwnerIndex=717|IndexInSheet=-1|OwnerPartId=-1|Color=8388608|FontID=1|IsHidden=T|Text=2D|Name=Available Preview Images
|RECORD=45|OwnerIndex=710|IndexInSheet=-1|Description=Chip Resistor, 2-Leads, Body 1.75x0.95mm, IPC High Density|UseComponentLibrary=T|ModelName=RESC1608X55X30LL15T15|ModelType=PCBLIB|DatafileCount=1|ModelDatafileEntity0=RESC1608X55X30LL15T15|ModelDatafileKind0=PCBLib|DatalinksLocked=T|DatabaseDatalinksLocked=T
|RECORD=46|OwnerIndex=719
|RECORD=48|OwnerIndex=719
|RECORD=41|OwnerIndex=721|IndexInSheet=-1|OwnerPartId=-1|Color=8388608|FontID=1|IsHidden=T|Text=2D|Name=Available Preview Images
|RECORD=17|IndexInSheet=60|OwnerPartId=-1|ShowNetName=T|Location.X=1040|Location.Y=840|Orientation=1|Color=128|FontID=1|Text=+3.3V
|RECORD=17|IndexInSheet=61|OwnerPartId=-1|ShowNetName=T|Location.X=1070|Location.Y=840|Orientation=1|Color=128|FontID=1|Text=+3.3V
|RECORD=17|IndexInSheet=62|OwnerPartId=-1|ShowNetName=T|Location.X=1030|Location.Y=695|Orientation=2|Color=255|FontID=1|Text=ANT3_IN|IsCrossSheetConnector=T
|RECORD=1|LibReference=CAP|ComponentDescription=C0603X104K5RACAUTO|PartCount=2|DisplayModeCount=2|IndexInSheet=63|OwnerPartId=-1|Location.X=1110|Location.Y=650|Orientation=3|CurrentPartId=1|SourceLibraryName=Altium Content Vault|TargetFileName=*|AreaColor=11599871|Color=128|PartIDLocked=F|DesignItemId=CMP-2006-00003-1|AllPinCount=2
|RECORD=2|OwnerIndex=726|OwnerPartId=1|OwnerPartDisplayMode=1|FormalType=1|Electrical=4|PinConglomerate=33|PinLength=10|Location.X=1100|Location.Y=650|Name=1|Designator=1|PinPropagationDelay=0.000000E+000
|RECORD=2|OwnerIndex=726|OwnerPartId=1|OwnerPartDisplayMode=1|FormalType=1|Electrical=4|PinConglomerate=35|PinLength=10|Location.X=1100|Location.Y=640|Name=2|Designator=2|PinPropagationDelay=0.000000E+000
|RECORD=13|OwnerIndex=726|IsNotAccesible=T|IndexInSheet=2|OwnerPartId=1|OwnerPartDisplayMode=1|Location.X=1092|Location.Y=650|Corner.X=1108|Corner.Y=650|LineWidth=1|Color=16711680
|RECORD=13|OwnerIndex=726|IsNotAccesible=T|IndexInSheet=3|OwnerPartId=1|OwnerPartDisplayMode=1|Location.X=1100|Location.Y=646|Corner.X=1100|Corner.Y=640|LineWidth=1|Color=16711680
|RECORD=12|OwnerIndex=726|IsNotAccesible=T|IndexInSheet=4|OwnerPartId=1|OwnerPartDisplayMode=1|Location.X=1100|Location.Y=630|Radius=16|LineWidth=1|StartAngle=61.000|EndAngle=90.000|Color=16711680
|RECORD=12|OwnerIndex=726|IsNotAccesible=T|IndexInSheet=5|OwnerPartId=1|OwnerPartDisplayMode=1|Location.X=1100|Location.Y=630|Radius=16|LineWidth=1|StartAngle=90.000|EndAngle=119.000|Color=16711680
|RECORD=2|OwnerIndex=726|OwnerPartId=1|FormalType=1|Electrical=4|PinConglomerate=33|PinLength=10|Location.X=1100|Location.Y=650|Name=1|Designator=1|PinPropagationDelay=0.000000E+000
|RECORD=2|OwnerIndex=726|OwnerPartId=1|FormalType=1|Electrical=4|PinConglomerate=35|PinLength=10|Location.X=1100|Location.Y=640|Name=2|Designator=2|PinPropagationDelay=0.000000E+000
|RECORD=13|OwnerIndex=726|IsNotAccesible=T|IndexInSheet=8|OwnerPartId=1|Location.X=1108|Location.Y=643|Corner.X=1092|Corner.Y=643|LineWidth=1|Color=16711680
|RECORD=13|OwnerIndex=726|IsNotAccesible=T|IndexInSheet=9|OwnerPartId=1|Location.X=1092|Location.Y=647|Corner.X=1108|Corner.Y=647|LineWidth=1|Color=16711680
|RECORD=6|OwnerIndex=726|IsNotAccesible=T|IndexInSheet=10|OwnerPartId=1|LineWidth=1|Color=16711680|LocationCount=2|X1=1100|Y1=650|X2=1100|Y2=647
|RECORD=6|OwnerIndex=726|IsNotAccesible=T|IndexInSheet=11|OwnerPartId=1|LineWidth=1|Color=16711680|LocationCount=2|X1=1100|Y1=640|X2=1100|Y2=643
|RECORD=41|OwnerIndex=726|IndexInSheet=12|OwnerPartId=-1|Location.X=1091|Location.Y=662|Color=8388608|FontID=1|IsHidden=T|Text=Kemet|Name=Manufacturer
|RECORD=41|OwnerIndex=726|IndexInSheet=13|OwnerPartId=-1|Location.X=1091|Location.Y=662|Color=8388608|FontID=1|IsHidden=T|Text=C0603X104K5RACAUTO|Name=Part Number
|RECORD=34|OwnerIndex=726|IndexInSheet=-1|OwnerPartId=-1|Location.X=1109|Location.Y=637|Color=8388608|FontID=1|Text=C27|Name=Designator|ReadOnlyState=1
|RECORD=41|OwnerIndex=726|IndexInSheet=-1|OwnerPartId=-1|Location.X=1109|Location.Y=623|Color=8388608|FontID=1|Text=0.1uF|Name=Comment
|RECORD=44|OwnerIndex=726
|RECORD=45|OwnerIndex=747|IndexInSheet=-1|Description=Chip Capacitor, 2-Leads, Body 1.60x0.80mm, IPC Low Density|UseComponentLibrary=T|ModelName=CAPC1608X87X45ML20T05|ModelType=PCBLIB|DatafileCount=1|ModelDatafileEntity0=CAPC1608X87X45ML20T05|ModelDatafileKind0=PCBLib|IsCurrent=T|DatalinksLocked=T|DatabaseDatalinksLocked=T
|RECORD=46|OwnerIndex=748
|RECORD=48|OwnerIndex=748
|RECORD=41|OwnerIndex=750|IndexInSheet=-1|OwnerPartId=-1|Color=8388608|FontID=1|Text=2D|Name=Available Preview Images
|RECORD=45|OwnerIndex=747|IndexInSheet=-1|Description=Chip Capacitor, 2-Leads, Body 1.60x0.80mm, IPC High Density|UseComponentLibrary=T|ModelName=CAPC1608X87X45LL20T05|ModelType=PCBLIB|DatafileCount=1|ModelDatafileEntity0=CAPC1608X87X45LL20T05|ModelDatafileKind0=PCBLib|DatalinksLocked=T|DatabaseDatalinksLocked=T
|RECORD=46|OwnerIndex=752
|RECORD=48|OwnerIndex=752
|RECORD=41|OwnerIndex=754|IndexInSheet=-1|OwnerPartId=-1|Color=8388608|FontID=1|Text=2D|Name=Available Preview Images
|RECORD=45|OwnerIndex=747|IndexInSheet=-1|Description=Chip Capacitor, 2-Leads, Body 1.60x0.80mm, IPC Medium Density|UseComponentLibrary=T|ModelName=CAPC1608X87X45NL20T05|ModelType=PCBLIB|DatafileCount=1|ModelDatafileEntity0=CAPC1608X87X45NL20T05|ModelDatafileKind0=PCBLib|DatalinksLocked=T|DatabaseDatalinksLocked=T
|RECORD=46|OwnerIndex=756
|RECORD=48|OwnerIndex=756
|RECORD=41|OwnerIndex=758|IndexInSheet=-1|OwnerPartId=-1|Color=8388608|FontID=1|Text=2D|Name=Available Preview Images
|RECORD=17|IndexInSheet=64|OwnerPartId=-1|Style=4|ShowNetName=T|Location.X=1150|Location.Y=620|Orientation=3|Color=128|FontID=1|Text=GND
|RECORD=17|IndexInSheet=65|OwnerPartId=-1|Style=4|ShowNetName=T|Location.X=1100|Location.Y=620|Orientation=3|Color=128|FontID=1|Text=GND
|RECORD=17|IndexInSheet=66|OwnerPartId=-1|ShowNetName=T|Location.X=1100|Location.Y=840|Orientation=1|Color=128|FontID=1|Text=+3.3V
|RECORD=1|LibReference=NC7WV125K8X|ComponentDescription=Integrated Circuit|PartCount=2|DisplayModeCount=1|IndexInSheet=67|OwnerPartId=-1|Location.X=1160|Location.Y=355|CurrentPartId=1|LibraryPath=*|SourceLibraryName=SamacSys.SchLib|TargetFileName=*|AreaColor=11599871|Color=128|PartIDLocked=T|DesignItemId=NC7WV125K8X|AllPinCount=8
|RECORD=41|OwnerIndex=763|OwnerPartId=-1|Location.X=1160|Location.Y=355|Color=8388608|FontID=6|IsHidden=T|Text=https://www.mouser.com/datasheet/2/308/NC7WV125-1301459.pdf|Name=Datasheet Link
|RECORD=41|OwnerIndex=763|IndexInSheet=1|OwnerPartId=-1|Location.X=1160|Location.Y=355|Color=8388608|FontID=1|IsHidden=T|Text=0.9mm|Name=Height
|RECORD=41|OwnerIndex=763|IndexInSheet=2|OwnerPartId=-1|Location.X=1160|Location.Y=355|Color=8388608|FontID=1|IsHidden=T|Text=ON Semiconductor|Name=Manufacturer_Name
|RECORD=41|OwnerIndex=763|IndexInSheet=3|OwnerPartId=-1|Location.X=1160|Location.Y=355|Color=8388608|FontID=1|IsHidden=T|Text=NC7WV125K8X|Name=Manufacturer_Part_Number
|RECORD=41|OwnerIndex=763|IndexInSheet=4|OwnerPartId=-1|Location.X=1160|Location.Y=355|Color=8388608|FontID=1|IsHidden=T|Text=512-NC7WV125K8X|Name=Mouser Part Number
|RECORD=41|OwnerIndex=763|IndexInSheet=5|OwnerPartId=-1|Location.X=1160|Location.Y=355|Color=8388608|FontID=6|IsHidden=T|Text=https://www.mouser.com/Search/Refine.aspx?Keyword=512-NC7WV125K8X|Name=Mouser Price/Stock
|RECORD=41|OwnerIndex=763|IndexInSheet=6|OwnerPartId=-1|Location.X=1160|Location.Y=355|Color=8388608|FontID=1|IsHidden=T|Text=NC7WV125K8X|Name=Arrow Part Number
|RECORD=41|OwnerIndex=763|IndexInSheet=7|OwnerPartId=-1|Location.X=1160|Location.Y=355|Color=8388608|FontID=6|IsHidden=T|Text=https://www.arrow.com/en/products/nc7wv125k8x/on-semiconductor|Name=Arrow Price/Stock
|RECORD=14|OwnerIndex=763|IsNotAccesible=T|IndexInSheet=8|OwnerPartId=1|Location.X=1180|Location.Y=330|Corner.X=1250|Corner.Y=455|LineWidth=1|Color=128|AreaColor=11599871|IsSolid=T
|RECORD=2|OwnerIndex=763|OwnerPartId=1|FormalType=1|Electrical=4|PinConglomerate=58|PinLength=20|Location.X=1180|Location.Y=445|Designator=1|SwapIDPart=Ž&Ž||PinPropagationDelay=0.000000E+000
|RECORD=2|OwnerIndex=763|OwnerPartId=1|FormalType=1|Electrical=4|PinConglomerate=58|PinLength=20|Location.X=1180|Location.Y=420|Designator=2|SwapIDPart=Ž&Ž||PinPropagationDelay=0.000000E+000
|RECORD=2|OwnerIndex=763|OwnerPartId=1|FormalType=1|Electrical=4|PinConglomerate=58|PinLength=20|Location.X=1180|Location.Y=365|Designator=3|SwapIDPart=Ž&Ž||PinPropagationDelay=0.000000E+000
|RECORD=2|OwnerIndex=763|OwnerPartId=1|FormalType=1|Electrical=4|PinConglomerate=58|PinLength=20|Location.X=1180|Location.Y=335|Name=GND|Designator=4|SwapIDPart=Ž&Ž||PinPropagationDelay=0.000000E+000
|RECORD=2|OwnerIndex=763|OwnerPartId=1|FormalType=1|Electrical=4|PinConglomerate=58|PinLength=20|Location.X=1180|Location.Y=345|Name=VCC|Designator=8|SwapIDPart=Ž&Ž||PinPropagationDelay=0.000000E+000
|RECORD=2|OwnerIndex=763|OwnerPartId=1|FormalType=1|Electrical=4|PinConglomerate=58|PinLength=20|Location.X=1180|Location.Y=390|Designator=7|SwapIDPart=Ž&Ž||PinPropagationDelay=0.000000E+000
|RECORD=2|OwnerIndex=763|OwnerPartId=1|FormalType=1|Electrical=4|PinConglomerate=56|PinLength=20|Location.X=1250|Location.Y=420|Designator=6|SwapIDPart=Ž&Ž||PinPropagationDelay=0.000000E+000
|RECORD=2|OwnerIndex=763|OwnerPartId=1|FormalType=1|Electrical=4|PinConglomerate=56|PinLength=20|Location.X=1250|Location.Y=365|Designator=5|SwapIDPart=Ž&Ž||PinPropagationDelay=0.000000E+000
|RECORD=6|OwnerIndex=763|IsNotAccesible=T|IndexInSheet=17|OwnerPartId=1|LineWidth=1|Color=16711680|LocationCount=4|X1=1205|Y1=430|X2=1205|Y2=410|X3=1225|Y3=420|X4=1205|Y4=430
|RECORD=12|OwnerIndex=763|IsNotAccesible=T|IndexInSheet=18|OwnerPartId=1|Location.X=1215|Location.Y=427|Radius=1|Radius_Frac=79777|LineWidth=1|EndAngle=360.000|Color=16711680
|RECORD=6|OwnerIndex=763|IsNotAccesible=T|IndexInSheet=19|OwnerPartId=1|LineWidth=1|Color=16711680|LocationCount=4|X1=1225|Y1=375|X2=1225|Y2=355|X3=1205|Y3=365|X4=1225|Y4=375
|RECORD=12|OwnerIndex=763|IsNotAccesible=T|IndexInSheet=20|OwnerPartId=1|Location.X=1215|Location.Y=372|Radius=1|Radius_Frac=79777|LineWidth=1|EndAngle=360.000|Color=16711680
|RECORD=6|OwnerIndex=763|IsNotAccesible=T|IndexInSheet=21|OwnerPartId=1|LineWidth=1|Color=16711680|LocationCount=3|X1=1215|Y1=374|X2=1215|Y2=390|X3=1180|Y3=390
|RECORD=6|OwnerIndex=763|IsNotAccesible=T|IndexInSheet=22|OwnerPartId=1|LineWidth=1|Color=16711680|LocationCount=3|X1=1215|Y1=429|X2=1215|Y2=445|X3=1180|Y3=445
|RECORD=6|OwnerIndex=763|IsNotAccesible=T|IndexInSheet=23|OwnerPartId=1|LineWidth=1|Color=16711680|LocationCount=2|X1=1180|Y1=420|X2=1205|Y2=420
|RECORD=6|OwnerIndex=763|IsNotAccesible=T|IndexInSheet=24|OwnerPartId=1|LineWidth=1|Color=16711680|LocationCount=2|X1=1225|Y1=420|X2=1250|Y2=420
|RECORD=6|OwnerIndex=763|IsNotAccesible=T|IndexInSheet=25|OwnerPartId=1|LineWidth=1|Color=16711680|LocationCount=2|X1=1225|Y1=365|X2=1250|Y2=365
|RECORD=6|OwnerIndex=763|IsNotAccesible=T|IndexInSheet=26|OwnerPartId=1|LineWidth=1|Color=16711680|LocationCount=2|X1=1205|Y1=365|X2=1180|Y2=365
|RECORD=34|OwnerIndex=763|IndexInSheet=-1|OwnerPartId=-1|Location.X=1179|Location.Y=455|Color=8388608|FontID=1|Text=U16|Name=Designator|ReadOnlyState=1
|RECORD=41|OwnerIndex=763|IndexInSheet=-1|OwnerPartId=-1|Location.X=1179|Location.Y=320|Color=8388608|FontID=1|Text=NC7WV125K8X|Name=Comment
|RECORD=44|OwnerIndex=763
|RECORD=45|OwnerIndex=801|IndexInSheet=-1|ModelName=SOP50P310X90-8N|ModelType=PCBLIB|DatafileCount=1|ModelDatafile0=C:\Users\<user>\Documents\AltiumLL\SamacSys.PcbLib|ModelDatafileEntity0=SOP50P310X90-8N|ModelDatafileKind0=PCBLIB|IsCurrent=T
|RECORD=46|OwnerIndex=802
|RECORD=48|OwnerIndex=802
|RECORD=17|IndexInSheet=68|OwnerPartId=-1|Style=4|ShowNetName=T|Location.X=1470|Location.Y=290|Orientation=3|Color=128|FontID=1|Text=GND
|RECORD=1|LibReference=CN-1P-M-RF3|ComponentDescription=Ultra Miniature Coaxial Connector Jack, 60 V, 50 Ohm, -40 to 90 degC, RoHS, Tape and Reel|PartCount=2|DisplayModeCount=1|IndexInSheet=69|OwnerPartId=-1|Location.X=1400|Location.Y=440|CurrentPartId=1|LibraryPath=*|SourceLibraryName=Altium Content Vault|TargetFileName=*|AreaColor=11599871|Color=128|PartIDLocked=T|DesignItemId=CMP-2000-07505-1|AllPinCount=3
|RECORD=8|OwnerIndex=806|IsNotAccesible=T|OwnerPartId=1|Location.X=1420|Location.Y=420|Radius=20|SecondaryRadius=20|LineWidth=1|Color=16711680|AreaColor=16777215
|RECORD=8|OwnerIndex=806|IsNotAccesible=T|IndexInSheet=1|OwnerPartId=1|Location.X=1420|Location.Y=420|Radius=4|SecondaryRadius=4|LineWidth=1|Color=16711680|AreaColor=16777215
|RECORD=2|OwnerIndex=806|OwnerPartId=1|FormalType=1|Electrical=4|PinConglomerate=51|PinLength=10|Location.X=1410|Location.Y=400|Name=1|Designator=1|PinPropagationDelay=0.000000E+000
|RECORD=2|OwnerIndex=806|OwnerPartId=1|FormalType=1|Electrical=4|PinConglomerate=50|PinLength=10|Location.X=1400|Location.Y=420|Name=2|Designator=2|PinPropagationDelay=0.000000E+000
|RECORD=2|OwnerIndex=806|OwnerPartId=1|FormalType=1|Electrical=4|PinConglomerate=51|PinLength=10|Location.X=1430|Location.Y=400|Name=3|Designator=3|PinPropagationDelay=0.000000E+000
|RECORD=6|OwnerIndex=806|IsNotAccesible=T|IndexInSheet=5|OwnerPartId=1|LineWidth=1|Color=16711680|LocationCount=5|X1=1400|Y1=400|X2=1400|Y2=440|X3=1440|Y3=440|X4=1440|Y4=400|X5=1400|Y5=400
|RECORD=6|OwnerIndex=806|IsNotAccesible=T|IndexInSheet=6|OwnerPartId=1|LineWidth=1|Color=16711680|LocationCount=2|X1=1400|Y1=420|X2=1416|Y2=420
|RECORD=41|OwnerIndex=806|IndexInSheet=7|OwnerPartId=-1|Location.X=1388|Location.Y=441|Color=8388608|FontID=1|IsHidden=T|Text=Straight|Name=Orientation
|RECORD=41|OwnerIndex=806|IndexInSheet=8|OwnerPartId=-1|Location.X=1388|Location.Y=441|Color=8388608|FontID=1|IsHidden=T|Text=Female|Name=Gender
|RECORD=41|OwnerIndex=806|IndexInSheet=9|OwnerPartId=-1|Location.X=1388|Location.Y=441|Color=8388608|FontID=1|IsHidden=T|Text=Vertical|Name=PCB Mounting Orientation
|RECORD=41|OwnerIndex=806|IndexInSheet=10|OwnerPartId=-1|Location.X=1388|Location.Y=441|Color=8388608|FontID=1|IsHidden=T|Text=SurfaceMount|Name=Mount
|RECORD=41|OwnerIndex=806|IndexInSheet=11|OwnerPartId=-1|Location.X=1388|Location.Y=441|Color=8388608|FontID=1|IsHidden=T|Text=3mm|Name=Length
|RECORD=41|OwnerIndex=806|IndexInSheet=12|OwnerPartId=-1|Location.X=1388|Location.Y=441|Color=8388608|FontID=1|IsHidden=T|Text=TapeandReel|Name=Packaging
|RECORD=41|OwnerIndex=806|IndexInSheet=13|OwnerPartId=-1|Location.X=1388|Location.Y=441|Color=8388608|FontID=1|IsHidden=T|Text=Jack|Name=Connector Type
|RECORD=41|OwnerIndex=806|IndexInSheet=14|OwnerPartId=-1|Location.X=1388|Location.Y=441|Color=8388608|FontID=1|IsHidden=T|Text=LeadFree|Name=Lead Free
|RECORD=41|OwnerIndex=806|IndexInSheet=15|OwnerPartId=-1|Location.X=1388|Location.Y=441|Color=8388608|FontID=1|IsHidden=T|Text=1|Name=Package Quantity
|RECORD=41|OwnerIndex=806|IndexInSheet=16|OwnerPartId=-1|Location.X=1388|Location.Y=441|Color=8388608|FontID=1|IsHidden=T|Text=SMD/SMT|Name=Termination
|RECORD=41|OwnerIndex=806|IndexInSheet=17|OwnerPartId=-1|Location.X=1388|Location.Y=441|Color=8388608|FontID=1|IsHidden=T|Text=CopperAlloy|Name=Contact Material
|RECORD=41|OwnerIndex=806|IndexInSheet=18|OwnerPartId=-1|Location.X=1388|Location.Y=441|Color=8388608|FontID=1|IsHidden=T|Text=Pull|Name=Fastening Type
|RECORD=41|OwnerIndex=806|IndexInSheet=19|OwnerPartId=-1|Location.X=1388|Location.Y=441|Color=8388608|FontID=1|IsHidden=T|Text=true|Name=RoHSCompliant
|RECORD=41|OwnerIndex=806|IndexInSheet=20|OwnerPartId=-1|Location.X=1388|Location.Y=441|Color=8388608|FontID=1|IsHidden=T|Text=LiquidCrystalPolymer|Name=Body Material
|RECORD=41|OwnerIndex=806|IndexInSheet=21|OwnerPartId=-1|Location.X=1388|Location.Y=441|Color=8388608|FontID=1|IsHidden=T|Text=SMD/SMT|Name=Case\/Package
|RECORD=41|OwnerIndex=806|IndexInSheet=22|OwnerPartId=-1|Location.X=1388|Location.Y=441|Color=8388608|FontID=1|IsHidden=T|Text=90degC|Name=Max Operating Temperature
|RECORD=41|OwnerIndex=806|IndexInSheet=23|OwnerPartId=-1|Location.X=1388|Location.Y=441|Color=8388608|FontID=1|IsHidden=T|Text=50Ohm|Name=Impedance
|RECORD=41|OwnerIndex=806|IndexInSheet=24|OwnerPartId=-1|Location.X=1388|Location.Y=441|Color=8388608|FontID=6|IsHidden=T|Text=http://www.te.com/commerce/DocumentDelivery/DDEController?Action=srchrtrv&DocNm=1909763&DocType=Customer+Drawing&DocLang=English|Name=Datasheet URL
|RECORD=41|OwnerIndex=806|IndexInSheet=25|OwnerPartId=-1|Location.X=1388|Location.Y=441|Color=8388608|FontID=1|IsHidden=T|Text=Gold|Name=Contact Plating
|RECORD=41|OwnerIndex=806|IndexInSheet=26|OwnerPartId=-1|Location.X=1388|Location.Y=441|Color=8388608|FontID=1|IsHidden=T|Text=SurfaceMount|Name=Mounting Technology
|RECORD=41|OwnerIndex=806|IndexInSheet=27|OwnerPartId=-1|Location.X=1388|Location.Y=441|Color=8388608|FontID=1|IsHidden=T|Text=6GHz|Name=Max Frequency
|RECORD=41|OwnerIndex=806|IndexInSheet=28|OwnerPartId=-1|Location.X=1388|Location.Y=441|Color=8388608|FontID=1|IsHidden=T|Text=TECO-1909763-1|Name=Package Reference
|RECORD=41|OwnerIndex=806|IndexInSheet=29|OwnerPartId=-1|Location.X=1388|Location.Y=441|Color=8388608|FontID=1|IsHidden=T|Text=Thermoplastic|Name=Insulation Material
|RECORD=41|OwnerIndex=806|IndexInSheet=30|OwnerPartId=-1|Location.X=1388|Location.Y=441|Color=8388608|FontID=1|IsHidden=T|Text=-40degC|Name=Min Operating Temperature
|RECORD=41|OwnerIndex=806|IndexInSheet=31|OwnerPartId=-1|Location.X=1388|Location.Y=441|Color=8388608|FontID=6|IsHidden=T|Text=http://www.te.com/|Name=Manufacturer URL
|RECORD=41|OwnerIndex=806|IndexInSheet=32|OwnerPartId=-1|Location.X=1388|Location.Y=441|Color=8388608|FontID=1|IsHidden=T|Text=Gold|Name=Body Plating
|RECORD=41|OwnerIndex=806|IndexInSheet=33|OwnerPartId=-1|Location.X=1388|Location.Y=441|Color=8388608|FontID=1|IsHidden=T|Text=Polymer|Name=Dielectric Material
|RECORD=41|OwnerIndex=806|IndexInSheet=34|OwnerPartId=-1|Location.X=1388|Location.Y=441|Color=8388608|FontID=1|IsHidden=T|Text=TE Connectivity|Name=Manufacturer
|RECORD=41|OwnerIndex=806|IndexInSheet=35|OwnerPartId=-1|Location.X=1388|Location.Y=441|Color=8388608|FontID=1|IsHidden=T|Text=Compliant|Name=ELV
|RECORD=41|OwnerIndex=806|IndexInSheet=36|OwnerPartId=-1|Location.X=1388|Location.Y=441|Color=8388608|FontID=1|IsHidden=T|Text=Rev. B2, 11/2015|Name=Datasheet Version
|RECORD=41|OwnerIndex=806|IndexInSheet=37|OwnerPartId=-1|Location.X=1388|Location.Y=441|Color=8388608|FontID=1|IsHidden=T|Text=No|Name=Radiation Hardening
|RECORD=41|OwnerIndex=806|IndexInSheet=38|OwnerPartId=-1|Location.X=1388|Location.Y=441|Color=8388608|FontID=1|IsHidden=T|Text=3-Pin Surface Mount Device, Body 2.6 x 2.6 mm|Name=Package Description
|RECORD=41|OwnerIndex=806|IndexInSheet=39|OwnerPartId=-1|Location.X=1388|Location.Y=441|Color=8388608|FontID=1|IsHidden=T|Text=Beige|Name=Housing Colour
|RECORD=34|OwnerIndex=806|IndexInSheet=-1|OwnerPartId=-1|Location.X=1399|Location.Y=441|Color=8388608|FontID=1|Text=J4|Name=Designator|ReadOnlyState=1
|RECORD=41|OwnerIndex=806|IndexInSheet=-1|OwnerPartId=-1|Location.X=1450|Location.Y=400|Color=8388608|FontID=1|Text=1909763-1|Name=Comment
|RECORD=44|OwnerIndex=806
|RECORD=45|OwnerIndex=852|IndexInSheet=-1|Description=SMD, 3-Leads, Body 2.6x2.6mm, Height 1.25mm|UseComponentLibrary=T|ModelName=TECO-1909763-1_V|ModelType=PCBLIB|DatafileCount=1|ModelDatafileEntity0=TECO-1909763-1_V|ModelDatafileKind0=PCBLib|IsCurrent=T|DatalinksLocked=T|DatabaseDatalinksLocked=T
|RECORD=46|OwnerIndex=853
|RECORD=48|OwnerIndex=853
|RECORD=41|OwnerIndex=855|IndexInSheet=-1|OwnerPartId=-1|Color=8388608|FontID=1|Text=2D|Name=Available Preview Images
|RECORD=1|LibReference=CN-S-4F-RF5|ComponentDescription=Coaxial connector, 50 Ohm, -65 to 165 degC, 5-Pin THD, RoHS, Bulk|PartCount=2|DisplayModeCount=1|IndexInSheet=70|OwnerPartId=-1|Location.X=1400|Location.Y=360|CurrentPartId=1|LibraryPath=*|SourceLibraryName=Altium Content Vault|TargetFileName=*|AreaColor=11599871|Color=128|PartIDLocked=T|DesignItemId=CMP-2000-05705-1|AllPinCount=5
|RECORD=2|OwnerIndex=857|OwnerPartId=1|FormalType=1|Electrical=4|PinConglomerate=51|PinLength=10|Location.X=1440|Location.Y=320|Name=5|Designator=5|SwapIDPart=Ž&Ž1|PinPropagationDelay=0.000000E+000
|RECORD=8|OwnerIndex=857|IsNotAccesible=T|IndexInSheet=1|OwnerPartId=1|Location.X=1420|Location.Y=340|Radius=20|SecondaryRadius=20|LineWidth=1|Color=16711680|AreaColor=16777215
|RECORD=8|OwnerIndex=857|IsNotAccesible=T|IndexInSheet=2|OwnerPartId=1|Location.X=1420|Location.Y=340|Radius=4|SecondaryRadius=4|LineWidth=1|Color=16711680|AreaColor=16777215
|RECORD=2|OwnerIndex=857|OwnerPartId=1|FormalType=1|Electrical=4|PinConglomerate=50|PinLength=10|Location.X=1400|Location.Y=340|Name=1|Designator=1|PinPropagationDelay=0.000000E+000
|RECORD=2|OwnerIndex=857|OwnerPartId=1|FormalType=1|Electrical=4|PinConglomerate=51|PinLength=10|Location.X=1410|Location.Y=320|Name=2|Designator=2|PinPropagationDelay=0.000000E+000
|RECORD=2|OwnerIndex=857|OwnerPartId=1|FormalType=1|Electrical=4|PinConglomerate=51|PinLength=10|Location.X=1420|Location.Y=320|Name=3|Designator=3|PinPropagationDelay=0.000000E+000
|RECORD=2|OwnerIndex=857|OwnerPartId=1|FormalType=1|Electrical=4|PinConglomerate=51|PinLength=10|Location.X=1430|Location.Y=320|Name=4|Designator=4|PinPropagationDelay=0.000000E+000
|RECORD=6|OwnerIndex=857|IsNotAccesible=T|IndexInSheet=7|OwnerPartId=1|LineWidth=1|Color=16711680|LocationCount=5|X1=1400|Y1=320|X2=1400|Y2=360|X3=1440|Y3=360|X4=1440|Y4=320|X5=1400|Y5=320
|RECORD=6|OwnerIndex=857|IsNotAccesible=T|IndexInSheet=8|OwnerPartId=1|LineWidth=1|Color=16711680|LocationCount=2|X1=1400|Y1=340|X2=1416|Y2=340
|RECORD=41|OwnerIndex=857|IndexInSheet=9|OwnerPartId=-1|Location.X=1388|Location.Y=361|Color=8388608|FontID=1|IsHidden=T|Text=ThroughHole|Name=Mounting Technology
|RECORD=41|OwnerIndex=857|IndexInSheet=10|OwnerPartId=-1|Location.X=1388|Location.Y=361|Color=8388608|FontID=1|IsHidden=T|Text=ThroughHole,RightAngle|Name=Mounting Type
|RECORD=41|OwnerIndex=857|IndexInSheet=11|OwnerPartId=-1|Location.X=1388|Location.Y=361|Color=8388608|FontID=1|IsHidden=T|Text=-|Name=Cable Group
|RECORD=41|OwnerIndex=857|IndexInSheet=12|OwnerPartId=-1|Location.X=1388|Location.Y=361|Color=8388608|FontID=1|IsHidden=T|Text=901-143-6RFXMountingHole|Name=Catalog Drawings
|RECORD=41|OwnerIndex=857|IndexInSheet=13|OwnerPartId=-1|Location.X=1388|Location.Y=361|Color=8388608|FontID=1|IsHidden=T|Text=901-143-6RFX.igs|Name=3D Model
|RECORD=41|OwnerIndex=857|IndexInSheet=14|OwnerPartId=-1|Location.X=1388|Location.Y=361|Color=8388608|FontID=1|IsHidden=T|Text=-|Name=Series
|RECORD=41|OwnerIndex=857|IndexInSheet=15|OwnerPartId=-1|Location.X=1388|Location.Y=361|Color=8388608|FontID=1|IsHidden=T|Text=5-Pin Through Hole Device, Body 7 x 7 mm, Pitch 2.54 mm|Name=Package Description
|RECORD=41|OwnerIndex=857|IndexInSheet=16|OwnerPartId=-1|Location.X=1388|Location.Y=361|Color=8388608|FontID=1|IsHidden=T|Text=901-143-6RFX|Name=Package Reference
|RECORD=41|OwnerIndex=857|IndexInSheet=17|OwnerPartId=-1|Location.X=1388|Location.Y=361|Color=8388608|FontID=1|IsHidden=T|Text=Brass|Name=Body Material
|RECORD=41|OwnerIndex=857|IndexInSheet=18|OwnerPartId=-1|Location.X=1388|Location.Y=361|Color=8388608|FontID=1|IsHidden=T|Text=-|Name=Voltage Rating
|RECORD=41|OwnerIndex=857|IndexInSheet=19|OwnerPartId=-1|Location.X=1388|Location.Y=361|Color=8388608|FontID=1|IsHidden=T|Text=1|Name=Standard Package
|RECORD=41|OwnerIndex=857|IndexInSheet=20|OwnerPartId=-1|Location.X=1388|Location.Y=361|Color=8388608|FontID=1|IsHidden=T|Text=Jack,FemaleSocket|Name=Connector Type
|RECORD=41|OwnerIndex=857|IndexInSheet=21|OwnerPartId=-1|Location.X=1388|Location.Y=361|Color=8388608|FontID=1|IsHidden=T|Text=Threaded|Name=Fastening Type
|RECORD=41|OwnerIndex=857|IndexInSheet=22|OwnerPartId=-1|Location.X=1388|Location.Y=361|Color=8388608|FontID=1|IsHidden=T|Text=Gold|Name=Housing Color
|RECORD=41|OwnerIndex=857|IndexInSheet=23|OwnerPartId=-1|Location.X=1388|Location.Y=361|Color=8388608|FontID=1|IsHidden=T|Text=Solder|Name=Shield Termination
|RECORD=41|OwnerIndex=857|IndexInSheet=24|OwnerPartId=-1|Location.X=1388|Location.Y=361|Color=8388608|FontID=1|IsHidden=T|Text=901-143-6-RFX9011436RFXARFX1232|Name=Other Names
|RECORD=41|OwnerIndex=857|IndexInSheet=25|OwnerPartId=-1|Location.X=1388|Location.Y=361|Color=8388608|FontID=6|IsHidden=T|Text=http://www.amphenolrf.com/downloads/dl/file/id/2712/product/3102/901_143_6rfx_customer_drawing.pdf|Name=Datasheet URL
|RECORD=41|OwnerIndex=857|IndexInSheet=26|OwnerPartId=-1|Location.X=1388|Location.Y=361|Color=8388608|FontID=1|IsHidden=T|Text=CoaxialConnectors(RF)|Name=Family
|RECORD=41|OwnerIndex=857|IndexInSheet=27|OwnerPartId=-1|Location.X=1388|Location.Y=361|Color=8388608|FontID=1|IsHidden=T|Text=SMA,RFX|Name=Online Catalog
|RECORD=41|OwnerIndex=857|IndexInSheet=28|OwnerPartId=-1|Location.X=1388|Location.Y=361|Color=8388608|FontID=1|IsHidden=T|Text=18GHz|Name=Frequency - Max
|RECORD=41|OwnerIndex=857|IndexInSheet=29|OwnerPartId=-1|Location.X=1388|Location.Y=361|Color=8388608|FontID=1|IsHidden=T|Text=Solder|Name=Contact Termination
|RECORD=41|OwnerIndex=857|IndexInSheet=30|OwnerPartId=-1|Location.X=1388|Location.Y=361|Color=8388608|FontID=6|IsHidden=T|Text=http://www.amphenol.com/|Name=Manufacturer URL
|RECORD=41|OwnerIndex=857|IndexInSheet=31|OwnerPartId=-1|Location.X=1388|Location.Y=361|Color=8388608|FontID=1|IsHidden=T|Text=Amphenol|Name=Manufacturer
|RECORD=41|OwnerIndex=857|IndexInSheet=32|OwnerPartId=-1|Location.X=1388|Location.Y=361|Color=8388608|FontID=1|IsHidden=T|Text=-65°C~165°C|Name=Operating Temperature
|RECORD=41|OwnerIndex=857|IndexInSheet=33|OwnerPartId=-1|Location.X=1388|Location.Y=361|Color=8388608|FontID=1|IsHidden=T|Text=Connectors,Interconnects|Name=Category
|RECORD=41|OwnerIndex=857|IndexInSheet=34|OwnerPartId=-1|Location.X=1388|Location.Y=361|Color=8388608|FontID=1|IsHidden=T|Text=Bulk|Name=Packaging
|RECORD=41|OwnerIndex=857|IndexInSheet=35|OwnerPartId=-1|Location.X=1388|Location.Y=361|Color=8388608|FontID=1|IsHidden=T|Text=Gold|Name=Body Finish
|RECORD=41|OwnerIndex=857|IndexInSheet=36|OwnerPartId=-1|Location.X=1388|Location.Y=361|Color=8388608|FontID=1|IsHidden=T|Text=Polytetrafluoroethylene(PTFE)|Name=Dielectric Material
|RECORD=41|OwnerIndex=857|IndexInSheet=37|OwnerPartId=-1|Location.X=1388|Location.Y=361|Color=8388608|FontID=1|IsHidden=T|Text=BerylliumCopper|Name=Center Contact Material
|RECORD=41|OwnerIndex=857|IndexInSheet=38|OwnerPartId=-1|Location.X=1388|Location.Y=361|Color=8388608|FontID=1|IsHidden=T|Text=50Ohm|Name=Impedance
|RECORD=41|OwnerIndex=857|IndexInSheet=39|OwnerPartId=-1|Location.X=1388|Location.Y=361|Color=8388608|FontID=1|IsHidden=T|Text=-|Name=Features
|RECORD=41|OwnerIndex=857|IndexInSheet=40|OwnerPartId=-1|Location.X=1388|Location.Y=361|Color=8388608|FontID=1|IsHidden=T|Text=SMA|Name=Connector Style
|RECORD=41|OwnerIndex=857|IndexInSheet=41|OwnerPartId=-1|Location.X=1388|Location.Y=361|Color=8388608|FontID=1|IsHidden=T|Text=Gold|Name=Center Contact Plating
|RECORD=41|OwnerIndex=857|IndexInSheet=42|OwnerPartId=-1|Location.X=1388|Location.Y=361|Color=8388608|FontID=1|IsHidden=T|Text=Rev. C, 06/2010|Name=Datasheet Version
|RECORD=41|OwnerIndex=857|IndexInSheet=43|OwnerPartId=-1|Location.X=1388|Location.Y=361|Color=8388608|FontID=1|IsHidden=T|Text=-|Name=Ingress Protection
|RECORD=34|OwnerIndex=857|IndexInSheet=-1|OwnerPartId=-1|Location.X=1399|Location.Y=361|Color=8388608|FontID=1|Text=AN4|Name=Designator|ReadOnlyState=1
|RECORD=41|OwnerIndex=857|IndexInSheet=-1|OwnerPartId=-1|Location.X=1450|Location.Y=310|Color=8388608|FontID=1|Text=901-143-6RFX|Name=Comment
|RECORD=44|OwnerIndex=857
|RECORD=45|OwnerIndex=909|IndexInSheet=-1|Description=THD, 5-Leads, Body 7x7mm, Pitch 2.54mm|UseComponentLibrary=T|ModelName=AMPH-901-143-6RFX_V|ModelType=PCBLIB|DatafileCount=1|ModelDatafileEntity0=AMPH-901-143-6RFX_V|ModelDatafileKind0=PCBLib|IsCurrent=T|DatalinksLocked=T|DatabaseDatalinksLocked=T
|RECORD=46|OwnerIndex=910
|RECORD=48|OwnerIndex=910
|RECORD=41|OwnerIndex=912|IndexInSheet=-1|OwnerPartId=-1|Color=8388608|FontID=1|Text=2D|Name=Available Preview Images
|RECORD=17|IndexInSheet=71|OwnerPartId=-1|Style=4|ShowNetName=T|Location.X=1470|Location.Y=380|Orientation=3|Color=128|FontID=1|Text=GND
|RECORD=1|LibReference=RES-2|ComponentDescription=General Purpose Chip Resistor, 49.9 Ohm, +/- 1%, -55 to 155 degC, 0603 (1608 Metric), RoHS, Tape and Reel|PartCount=2|DisplayModeCount=1|IndexInSheet=72|OwnerPartId=-1|Location.X=1305|Location.Y=420|CurrentPartId=1|LibraryPath=*|SourceLibraryName=Altium Content Vault|TargetFileName=*|AreaColor=11599871|Color=128|PartIDLocked=T|DesignItemId=CMP-1659-00036-1|AllPinCount=2
|RECORD=2|OwnerIndex=915|OwnerPartId=1|FormalType=1|Electrical=4|PinConglomerate=32|PinLength=10|Location.X=1325|Location.Y=420|Name=2|Designator=2|PinPropagationDelay=0.000000E+000
|RECORD=2|OwnerIndex=915|OwnerPartId=1|FormalType=1|Electrical=4|PinConglomerate=34|PinLength=10|Location.X=1305|Location.Y=420|Name=1|Designator=1|PinPropagationDelay=0.000000E+000
|RECORD=6|OwnerIndex=915|IsNotAccesible=T|IndexInSheet=2|OwnerPartId=1|LineWidth=1|Color=16711680|LocationCount=10|X1=1325|Y1=420|X2=1321|Y2=420|X3=1320|Y3=418|X4=1318|Y4=422|X5=1316|Y5=418|X6=1314|Y6=422|X7=1312|Y7=418|X8=1310|Y8=422|X9=1309|Y9=420|X10=1305|Y10=420
|RECORD=41|OwnerIndex=915|IndexInSheet=3|OwnerPartId=-1|Location.X=1293|Location.Y=435|Color=8388608|FontID=1|IsHidden=T|Text=0603|Name=PackageReference
|RECORD=41|OwnerIndex=915|IndexInSheet=4|OwnerPartId=-1|Location.X=1293|Location.Y=435|Color=8388608|FontID=1|IsHidden=T|Text=Tray|Name=Packaging
|RECORD=41|OwnerIndex=915|IndexInSheet=5|OwnerPartId=-1|Location.X=1293|Location.Y=435|Color=8388608|FontID=1|IsHidden=T|Text=Datasheet|Name=ComponentLink2Description
|RECORD=41|OwnerIndex=915|IndexInSheet=6|OwnerPartId=-1|Location.X=1293|Location.Y=435|Color=8388608|FontID=1|IsHidden=T|Text=Manufacturer URL|Name=ComponentLink1Description
|RECORD=41|OwnerIndex=915|IndexInSheet=7|OwnerPartId=-1|Location.X=1293|Location.Y=435|Color=8388608|FontID=6|IsHidden=T|Text=https://datasheet.ciiva.com/11808/0900766b80f96399-11808223.pdf|Name=ComponentLink2URL
|RECORD=41|OwnerIndex=915|IndexInSheet=8|OwnerPartId=-1|Location.X=1293|Location.Y=435|Color=8388608|FontID=1|IsHidden=T|Text=true|Name=RoHSCompliant
|RECORD=41|OwnerIndex=915|IndexInSheet=9|OwnerPartId=-1|Location.X=1293|Location.Y=435|Color=8388608|FontID=1|IsHidden=T|Text=85 degC|Name=Max Operating Temperature
|RECORD=41|OwnerIndex=915|IndexInSheet=10|OwnerPartId=-1|Location.X=1293|Location.Y=435|Color=8388608|FontID=1|IsHidden=T|Text=3.63 V|Name=Max Supply Voltage
|RECORD=41|OwnerIndex=915|IndexInSheet=11|OwnerPartId=-1|Location.X=1293|Location.Y=435|Color=8388608|FontID=6|IsHidden=T|Text=http://www.yageo.com/|Name=ComponentLink1URL
|RECORD=41|OwnerIndex=915|IndexInSheet=12|OwnerPartId=-1|Location.X=1293|Location.Y=435|Color=8388608|FontID=1|IsHidden=T|Text=2-Pin Surface Mount Device, Body 1.6 x 0.8 mm|Name=PackageDescription
|RECORD=41|OwnerIndex=915|IndexInSheet=13|OwnerPartId=-1|Location.X=1293|Location.Y=435|Color=8388608|FontID=1|IsHidden=T|Text=LQFP|Name=Case\Package
|RECORD=41|OwnerIndex=915|IndexInSheet=14|OwnerPartId=-1|Location.X=1293|Location.Y=435|Color=8388608|FontID=1|IsHidden=T|Text=Rev. 4, 04/2009|Name=DatasheetVersion
|RECORD=41|OwnerIndex=915|IndexInSheet=15|OwnerPartId=-1|Location.X=1293|Location.Y=435|Color=8388608|FontID=1|IsHidden=T|Text=-40 degC|Name=Min Operating Temperature
|RECORD=41|OwnerIndex=915|IndexInSheet=16|OwnerPartId=-1|Location.X=1293|Location.Y=435|Color=8388608|FontID=1|IsHidden=T|Text=SPI|Name=Interface
|RECORD=41|OwnerIndex=915|IndexInSheet=17|OwnerPartId=-1|Location.X=1293|Location.Y=435|Color=8388608|FontID=1|IsHidden=T|Text=250|Name=Package Quantity
|RECORD=41|OwnerIndex=915|IndexInSheet=18|OwnerPartId=-1|Location.X=1293|Location.Y=435|Color=8388608|FontID=1|IsHidden=T|Text=2.97 V|Name=Min Supply Voltage
|RECORD=41|OwnerIndex=915|IndexInSheet=19|OwnerPartId=-1|Location.X=1293|Location.Y=435|Color=8388608|FontID=1|IsHidden=T|Text=48|Name=Pins
|RECORD=34|OwnerIndex=915|IndexInSheet=-1|OwnerPartId=-1|Location.X=1304|Location.Y=423|Color=8388608|FontID=1|Text=R34|Name=Designator|ReadOnlyState=1
|RECORD=41|OwnerIndex=915|IndexInSheet=-1|OwnerPartId=-1|Location.X=1304|Location.Y=407|Color=8388608|FontID=1|Text=49.9R|Name=Comment
|RECORD=44|OwnerIndex=915
|RECORD=45|OwnerIndex=940|IndexInSheet=-1|Description=Chip Resistor, 2-Leads, Body 1.70x0.90mm, IPC Medium Density|UseComponentLibrary=T|ModelName=RESC1608X55X25NL10T15|ModelType=PCBLIB|DatafileCount=1|ModelDatafileEntity0=RESC1608X55X25NL10T15|ModelDatafileKind0=PCBLib|IsCurrent=T|DatalinksLocked=T|DatabaseDatalinksLocked=T
|RECORD=46|OwnerIndex=941
|RECORD=48|OwnerIndex=941
|RECORD=41|OwnerIndex=943|IndexInSheet=-1|OwnerPartId=-1|Color=8388608|FontID=1|IsHidden=T|Text=2D|Name=Available Preview Images
|RECORD=45|OwnerIndex=940|IndexInSheet=-1|Description=Chip Resistor, 2-Leads, Body 1.70x0.90mm, IPC Low Density|UseComponentLibrary=T|ModelName=RESC1608X55X25ML10T15|ModelType=PCBLIB|DatafileCount=1|ModelDatafileEntity0=RESC1608X55X25ML10T15|ModelDatafileKind0=PCBLib|DatalinksLocked=T|DatabaseDatalinksLocked=T
|RECORD=46|OwnerIndex=945
|RECORD=48|OwnerIndex=945
|RECORD=41|OwnerIndex=947|IndexInSheet=-1|OwnerPartId=-1|Color=8388608|FontID=1|IsHidden=T|Text=2D|Name=Available Preview Images
|RECORD=45|OwnerIndex=940|IndexInSheet=-1|Description=Chip Resistor, 2-Leads, Body 1.70x0.90mm, IPC High Density|UseComponentLibrary=T|ModelName=RESC1608X55X25LL10T15|ModelType=PCBLIB|DatafileCount=1|ModelDatafileEntity0=RESC1608X55X25LL10T15|ModelDatafileKind0=PCBLib|DatalinksLocked=T|DatabaseDatalinksLocked=T
|RECORD=46|OwnerIndex=949
|RECORD=48|OwnerIndex=949
|RECORD=41|OwnerIndex=951|IndexInSheet=-1|OwnerPartId=-1|Color=8388608|FontID=1|IsHidden=T|Text=2D|Name=Available Preview Images
|RECORD=17|IndexInSheet=73|OwnerPartId=-1|ShowNetName=T|Location.X=1030|Location.Y=420|Orientation=2|Color=255|FontID=1|Text=ANT4_OUT|IsCrossSheetConnector=T
|RECORD=1|LibReference=RES-2|ComponentDescription=Precision Thick Film Chip Resistor, 4.7 KOhm, +/- 1%, -55 to 155 degC, 0603 (1608 Metric), RoHS, Tape and Reel ERJ-3EKF4701V|PartCount=2|DisplayModeCount=1|IndexInSheet=74|OwnerPartId=-1|Location.X=1040|Location.Y=480|Orientation=1|CurrentPartId=1|LibraryPath=*|SourceLibraryName=Altium Content Vault|TargetFileName=*|AreaColor=11599871|Color=128|PartIDLocked=T|DesignItemId=CMP-1012-00586-3|AllPinCount=2
|RECORD=2|OwnerIndex=954|OwnerPartId=1|FormalType=1|Electrical=4|PinConglomerate=33|PinLength=10|Location.X=1040|Location.Y=500|Name=2|Designator=2|PinPropagationDelay=0.000000E+000
|RECORD=2|OwnerIndex=954|OwnerPartId=1|FormalType=1|Electrical=4|PinConglomerate=35|PinLength=10|Location.X=1040|Location.Y=480|Name=1|Designator=1|PinPropagationDelay=0.000000E+000
|RECORD=6|OwnerIndex=954|IsNotAccesible=T|IndexInSheet=2|OwnerPartId=1|LineWidth=1|Color=16711680|LocationCount=10|X1=1040|Y1=500|X2=1040|Y2=496|X3=1042|Y3=495|X4=1038|Y4=493|X5=1042|Y5=491|X6=1038|Y6=489|X7=1042|Y7=487|X8=1038|Y8=485|X9=1040|Y9=484|X10=1040|Y10=480
|RECORD=41|OwnerIndex=954|IndexInSheet=3|OwnerPartId=-1|Location.X=1037|Location.Y=512|Color=8388608|FontID=1|IsHidden=T|Text=220 Ohm|Name=Resistance
|RECORD=41|OwnerIndex=954|IndexInSheet=4|OwnerPartId=-1|Location.X=1037|Location.Y=512|Color=8388608|FontID=1|IsHidden=T|Text=0603|Name=PackageReference
|RECORD=41|OwnerIndex=954|IndexInSheet=5|OwnerPartId=-1|Location.X=1037|Location.Y=512|Color=8388608|FontID=1|IsHidden=T|Text=50 V|Name=Voltage Rating
|RECORD=41|OwnerIndex=954|IndexInSheet=6|OwnerPartId=-1|Location.X=1037|Location.Y=512|Color=8388608|FontID=1|IsHidden=T|Text=125 degC|Name=Max Operating Temperature
|RECORD=41|OwnerIndex=954|IndexInSheet=7|OwnerPartId=-1|Location.X=1037|Location.Y=512|Color=8388608|FontID=1|IsHidden=T|Text=4|Name=Elements
|RECORD=41|OwnerIndex=954|IndexInSheet=8|OwnerPartId=-1|Location.X=1037|Location.Y=512|Color=8388608|FontID=1|IsHidden=T|Text=No SVHC|Name=REACH SVHC
|RECORD=41|OwnerIndex=954|IndexInSheet=9|OwnerPartId=-1|Location.X=1037|Location.Y=512|Color=8388608|FontID=1|IsHidden=T|Text=0.063 inch|Name=Width
|RECORD=41|OwnerIndex=954|IndexInSheet=10|OwnerPartId=-1|Location.X=1037|Location.Y=512|Color=8388608|FontID=1|IsHidden=T|Text=1205|Name=Case\Package
|RECORD=41|OwnerIndex=954|IndexInSheet=11|OwnerPartId=-1|Location.X=1037|Location.Y=512|Color=8388608|FontID=1|IsHidden=T|Text=0.126 inch|Name=Length
|RECORD=41|OwnerIndex=954|IndexInSheet=12|OwnerPartId=-1|Location.X=1037|Location.Y=512|Color=8388608|FontID=1|IsHidden=T|Text=0.024 inch|Name=Height
|RECORD=41|OwnerIndex=954|IndexInSheet=13|OwnerPartId=-1|Location.X=1037|Location.Y=512|Color=8388608|FontID=1|IsHidden=T|Text=Surface Mount|Name=Mount
|RECORD=41|OwnerIndex=954|IndexInSheet=14|OwnerPartId=-1|Location.X=1037|Location.Y=512|Color=8388608|FontID=1|IsHidden=T|Text=1|Name=Package Quantity
|RECORD=41|OwnerIndex=954|IndexInSheet=15|OwnerPartId=-1|Location.X=1037|Location.Y=512|Color=8388608|FontID=1|IsHidden=T|Text=Apr-15|Name=DatasheetVersion
|RECORD=41|OwnerIndex=954|IndexInSheet=16|OwnerPartId=-1|Location.X=1037|Location.Y=512|Color=8388608|FontID=1|IsHidden=T|Text=Manufacturer URL|Name=ComponentLink1Description
|RECORD=41|OwnerIndex=954|IndexInSheet=17|OwnerPartId=-1|Location.X=1037|Location.Y=512|Color=8388608|FontID=1|IsHidden=T|Text=-55 degC|Name=Min Operating Temperature
|RECORD=41|OwnerIndex=954|IndexInSheet=18|OwnerPartId=-1|Location.X=1037|Location.Y=512|Color=8388608|FontID=1|IsHidden=T|Text=Tape and Reel|Name=Packaging
|RECORD=41|OwnerIndex=954|IndexInSheet=19|OwnerPartId=-1|Location.X=1037|Location.Y=512|Color=8388608|FontID=1|IsHidden=T|Text=No|Name=Radiation Hardening
|RECORD=41|OwnerIndex=954|IndexInSheet=20|OwnerPartId=-1|Location.X=1037|Location.Y=512|Color=8388608|FontID=6|IsHidden=T|Text=http://industrial.panasonic.com/cdbs/www-data/pdf/RDA0000/AOA0000C86.pdf|Name=ComponentLink2URL
|RECORD=41|OwnerIndex=954|IndexInSheet=21|OwnerPartId=-1|Location.X=1037|Location.Y=512|Color=8388608|FontID=1|IsHidden=T|Text=3216|Name=Case Code (Metric)
|RECORD=41|OwnerIndex=954|IndexInSheet=22|OwnerPartId=-1|Location.X=1037|Location.Y=512|Color=8388608|FontID=1|IsHidden=T|Text=8|Name=Pins
|RECORD=41|OwnerIndex=954|IndexInSheet=23|OwnerPartId=-1|Location.X=1037|Location.Y=512|Color=8388608|FontID=1|IsHidden=T|Text=1206|Name=Case Code (Imperial)
|RECORD=41|OwnerIndex=954|IndexInSheet=24|OwnerPartId=-1|Location.X=1037|Location.Y=512|Color=8388608|FontID=1|IsHidden=T|Text=Thick Film|Name=Type (Resistor)
|RECORD=41|OwnerIndex=954|IndexInSheet=25|OwnerPartId=-1|Location.X=1037|Location.Y=512|Color=8388608|FontID=1|IsHidden=T|Text=true|Name=RoHSCompliant
|RECORD=41|OwnerIndex=954|IndexInSheet=26|OwnerPartId=-1|Location.X=1037|Location.Y=512|Color=8388608|FontID=1|IsHidden=T|Text=5%|Name=Tolerance
|RECORD=41|OwnerIndex=954|IndexInSheet=27|OwnerPartId=-1|Location.X=1037|Location.Y=512|Color=8388608|FontID=1|IsHidden=T|Text=Datasheet|Name=ComponentLink2Description
|RECORD=41|OwnerIndex=954|IndexInSheet=28|OwnerPartId=-1|Location.X=1037|Location.Y=512|Color=8388608|FontID=1|IsHidden=T|Text=2-Pin Surface Mount Device, Body 1.6 x 0.85 mm|Name=PackageDescription
|RECORD=41|OwnerIndex=954|IndexInSheet=29|OwnerPartId=-1|Location.X=1037|Location.Y=512|Color=8388608|FontID=6|IsHidden=T|Text=http://www.panasonic.com/|Name=ComponentLink1URL
|RECORD=41|OwnerIndex=954|IndexInSheet=30|OwnerPartId=-1|Location.X=1037|Location.Y=512|Color=8388608|FontID=1|IsHidden=T|Text=250 mW|Name=Power Rating
|RECORD=34|OwnerIndex=954|IndexInSheet=-1|OwnerPartId=-1|Location.X=1043|Location.Y=491|Color=8388608|FontID=1|Text=R31|Name=Designator|ReadOnlyState=1
|RECORD=41|OwnerIndex=954|IndexInSheet=-1|OwnerPartId=-1|Location.X=1043|Location.Y=481|Color=8388608|FontID=1|Text=4.7K|Name=Comment
|RECORD=44|OwnerIndex=954
|RECORD=45|OwnerIndex=990|IndexInSheet=-1|Description=Chip Resistor, 2-Leads, Body 1.75x0.95mm, IPC Medium Density|UseComponentLibrary=T|ModelName=RESC1608X55X30NL15T15|ModelType=PCBLIB|DatafileCount=1|ModelDatafileEntity0=RESC1608X55X30NL15T15|ModelDatafileKind0=PCBLib|IsCurrent=T|DatalinksLocked=T|DatabaseDatalinksLocked=T
|RECORD=46|OwnerIndex=991
|RECORD=48|OwnerIndex=991
|RECORD=41|OwnerIndex=993|IndexInSheet=-1|OwnerPartId=-1|Color=8388608|FontID=1|IsHidden=T|Text=2D|Name=Available Preview Images
|RECORD=45|OwnerIndex=990|IndexInSheet=-1|Description=Chip Resistor, 2-Leads, Body 1.75x0.95mm, IPC Low Density|UseComponentLibrary=T|ModelName=RESC1608X55X30ML15T15|ModelType=PCBLIB|DatafileCount=1|ModelDatafileEntity0=RESC1608X55X30ML15T15|ModelDatafileKind0=PCBLib|DatalinksLocked=T|DatabaseDatalinksLocked=T
|RECORD=46|OwnerIndex=995
|RECORD=48|OwnerIndex=995
|RECORD=41|OwnerIndex=997|IndexInSheet=-1|OwnerPartId=-1|Color=8388608|FontID=1|IsHidden=T|Text=2D|Name=Available Preview Images
|RECORD=45|OwnerIndex=990|IndexInSheet=-1|Description=Chip Resistor, 2-Leads, Body 1.75x0.95mm, IPC High Density|UseComponentLibrary=T|ModelName=RESC1608X55X30LL15T15|ModelType=PCBLIB|DatafileCount=1|ModelDatafileEntity0=RESC1608X55X30LL15T15|ModelDatafileKind0=PCBLib|DatalinksLocked=T|DatabaseDatalinksLocked=T
|RECORD=46|OwnerIndex=999
|RECORD=48|OwnerIndex=999
|RECORD=41|OwnerIndex=1001|IndexInSheet=-1|OwnerPartId=-1|Color=8388608|FontID=1|IsHidden=T|Text=2D|Name=Available Preview Images
|RECORD=1|LibReference=RES-2|ComponentDescription=Precision Thick Film Chip Resistor, 4.7 KOhm, +/- 1%, -55 to 155 degC, 0603 (1608 Metric), RoHS, Tape and Reel ERJ-3EKF4701V|PartCount=2|DisplayModeCount=1|IndexInSheet=75|OwnerPartId=-1|Location.X=1070|Location.Y=480|Orientation=1|CurrentPartId=1|LibraryPath=*|SourceLibraryName=Altium Content Vault|TargetFileName=*|AreaColor=11599871|Color=128|PartIDLocked=T|DesignItemId=CMP-1012-00586-3|AllPinCount=2
|RECORD=2|OwnerIndex=1003|OwnerPartId=1|FormalType=1|Electrical=4|PinConglomerate=33|PinLength=10|Location.X=1070|Location.Y=500|Name=2|Designator=2|PinPropagationDelay=0.000000E+000
|RECORD=2|OwnerIndex=1003|OwnerPartId=1|FormalType=1|Electrical=4|PinConglomerate=35|PinLength=10|Location.X=1070|Location.Y=480|Name=1|Designator=1|PinPropagationDelay=0.000000E+000
|RECORD=6|OwnerIndex=1003|IsNotAccesible=T|IndexInSheet=2|OwnerPartId=1|LineWidth=1|Color=16711680|LocationCount=10|X1=1070|Y1=500|X2=1070|Y2=496|X3=1072|Y3=495|X4=1068|Y4=493|X5=1072|Y5=491|X6=1068|Y6=489|X7=1072|Y7=487|X8=1068|Y8=485|X9=1070|Y9=484|X10=1070|Y10=480
|RECORD=41|OwnerIndex=1003|IndexInSheet=3|OwnerPartId=-1|Location.X=1067|Location.Y=512|Color=8388608|FontID=1|IsHidden=T|Text=220 Ohm|Name=Resistance
|RECORD=41|OwnerIndex=1003|IndexInSheet=4|OwnerPartId=-1|Location.X=1067|Location.Y=512|Color=8388608|FontID=1|IsHidden=T|Text=0603|Name=PackageReference
|RECORD=41|OwnerIndex=1003|IndexInSheet=5|OwnerPartId=-1|Location.X=1067|Location.Y=512|Color=8388608|FontID=1|IsHidden=T|Text=50 V|Name=Voltage Rating
|RECORD=41|OwnerIndex=1003|IndexInSheet=6|OwnerPartId=-1|Location.X=1067|Location.Y=512|Color=8388608|FontID=1|IsHidden=T|Text=125 degC|Name=Max Operating Temperature
|RECORD=41|OwnerIndex=1003|IndexInSheet=7|OwnerPartId=-1|Location.X=1067|Location.Y=512|Color=8388608|FontID=1|IsHidden=T|Text=4|Name=Elements
|RECORD=41|OwnerIndex=1003|IndexInSheet=8|OwnerPartId=-1|Location.X=1067|Location.Y=512|Color=8388608|FontID=1|IsHidden=T|Text=No SVHC|Name=REACH SVHC
|RECORD=41|OwnerIndex=1003|IndexInSheet=9|OwnerPartId=-1|Location.X=1067|Location.Y=512|Color=8388608|FontID=1|IsHidden=T|Text=0.063 inch|Name=Width
|RECORD=41|OwnerIndex=1003|IndexInSheet=10|OwnerPartId=-1|Location.X=1067|Location.Y=512|Color=8388608|FontID=1|IsHidden=T|Text=1205|Name=Case\Package
|RECORD=41|OwnerIndex=1003|IndexInSheet=11|OwnerPartId=-1|Location.X=1067|Location.Y=512|Color=8388608|FontID=1|IsHidden=T|Text=0.126 inch|Name=Length
|RECORD=41|OwnerIndex=1003|IndexInSheet=12|OwnerPartId=-1|Location.X=1067|Location.Y=512|Color=8388608|FontID=1|IsHidden=T|Text=0.024 inch|Name=Height
|RECORD=41|OwnerIndex=1003|IndexInSheet=13|OwnerPartId=-1|Location.X=1067|Location.Y=512|Color=8388608|FontID=1|IsHidden=T|Text=Surface Mount|Name=Mount
|RECORD=41|OwnerIndex=1003|IndexInSheet=14|OwnerPartId=-1|Location.X=1067|Location.Y=512|Color=8388608|FontID=1|IsHidden=T|Text=1|Name=Package Quantity
|RECORD=41|OwnerIndex=1003|IndexInSheet=15|OwnerPartId=-1|Location.X=1067|Location.Y=512|Color=8388608|FontID=1|IsHidden=T|Text=Apr-15|Name=DatasheetVersion
|RECORD=41|OwnerIndex=1003|IndexInSheet=16|OwnerPartId=-1|Location.X=1067|Location.Y=512|Color=8388608|FontID=1|IsHidden=T|Text=Manufacturer URL|Name=ComponentLink1Description
|RECORD=41|OwnerIndex=1003|IndexInSheet=17|OwnerPartId=-1|Location.X=1067|Location.Y=512|Color=8388608|FontID=1|IsHidden=T|Text=-55 degC|Name=Min Operating Temperature
|RECORD=41|OwnerIndex=1003|IndexInSheet=18|OwnerPartId=-1|Location.X=1067|Location.Y=512|Color=8388608|FontID=1|IsHidden=T|Text=Tape and Reel|Name=Packaging
|RECORD=41|OwnerIndex=1003|IndexInSheet=19|OwnerPartId=-1|Location.X=1067|Location.Y=512|Color=8388608|FontID=1|IsHidden=T|Text=No|Name=Radiation Hardening
|RECORD=41|OwnerIndex=1003|IndexInSheet=20|OwnerPartId=-1|Location.X=1067|Location.Y=512|Color=8388608|FontID=6|IsHidden=T|Text=http://industrial.panasonic.com/cdbs/www-data/pdf/RDA0000/AOA0000C86.pdf|Name=ComponentLink2URL
|RECORD=41|OwnerIndex=1003|IndexInSheet=21|OwnerPartId=-1|Location.X=1067|Location.Y=512|Color=8388608|FontID=1|IsHidden=T|Text=3216|Name=Case Code (Metric)
|RECORD=41|OwnerIndex=1003|IndexInSheet=22|OwnerPartId=-1|Location.X=1067|Location.Y=512|Color=8388608|FontID=1|IsHidden=T|Text=8|Name=Pins
|RECORD=41|OwnerIndex=1003|IndexInSheet=23|OwnerPartId=-1|Location.X=1067|Location.Y=512|Color=8388608|FontID=1|IsHidden=T|Text=1206|Name=Case Code (Imperial)
|RECORD=41|OwnerIndex=1003|IndexInSheet=24|OwnerPartId=-1|Location.X=1067|Location.Y=512|Color=8388608|FontID=1|IsHidden=T|Text=Thick Film|Name=Type (Resistor)
|RECORD=41|OwnerIndex=1003|IndexInSheet=25|OwnerPartId=-1|Location.X=1067|Location.Y=512|Color=8388608|FontID=1|IsHidden=T|Text=true|Name=RoHSCompliant
|RECORD=41|OwnerIndex=1003|IndexInSheet=26|OwnerPartId=-1|Location.X=1067|Location.Y=512|Color=8388608|FontID=1|IsHidden=T|Text=5%|Name=Tolerance
|RECORD=41|OwnerIndex=1003|IndexInSheet=27|OwnerPartId=-1|Location.X=1067|Location.Y=512|Color=8388608|FontID=1|IsHidden=T|Text=Datasheet|Name=ComponentLink2Description
|RECORD=41|OwnerIndex=1003|IndexInSheet=28|OwnerPartId=-1|Location.X=1067|Location.Y=512|Color=8388608|FontID=1|IsHidden=T|Text=2-Pin Surface Mount Device, Body 1.6 x 0.85 mm|Name=PackageDescription
|RECORD=41|OwnerIndex=1003|IndexInSheet=29|OwnerPartId=-1|Location.X=1067|Location.Y=512|Color=8388608|FontID=6|IsHidden=T|Text=http://www.panasonic.com/|Name=ComponentLink1URL
|RECORD=41|OwnerIndex=1003|IndexInSheet=30|OwnerPartId=-1|Location.X=1067|Location.Y=512|Color=8388608|FontID=1|IsHidden=T|Text=250 mW|Name=Power Rating
|RECORD=34|OwnerIndex=1003|IndexInSheet=-1|OwnerPartId=-1|Location.X=1073|Location.Y=491|Color=8388608|FontID=1|Text=R32|Name=Designator|ReadOnlyState=1
|RECORD=41|OwnerIndex=1003|IndexInSheet=-1|OwnerPartId=-1|Location.X=1073|Location.Y=481|Color=8388608|FontID=1|Text=4.7K|Name=Comment
|RECORD=44|OwnerIndex=1003
|RECORD=45|OwnerIndex=1039|IndexInSheet=-1|Description=Chip Resistor, 2-Leads, Body 1.75x0.95mm, IPC Medium Density|UseComponentLibrary=T|ModelName=RESC1608X55X30NL15T15|ModelType=PCBLIB|DatafileCount=1|ModelDatafileEntity0=RESC1608X55X30NL15T15|ModelDatafileKind0=PCBLib|IsCurrent=T|DatalinksLocked=T|DatabaseDatalinksLocked=T
|RECORD=46|OwnerIndex=1040
|RECORD=48|OwnerIndex=1040
|RECORD=41|OwnerIndex=1042|IndexInSheet=-1|OwnerPartId=-1|Color=8388608|FontID=1|IsHidden=T|Text=2D|Name=Available Preview Images
|RECORD=45|OwnerIndex=1039|IndexInSheet=-1|Description=Chip Resistor, 2-Leads, Body 1.75x0.95mm, IPC Low Density|UseComponentLibrary=T|ModelName=RESC1608X55X30ML15T15|ModelType=PCBLIB|DatafileCount=1|ModelDatafileEntity0=RESC1608X55X30ML15T15|ModelDatafileKind0=PCBLib|DatalinksLocked=T|DatabaseDatalinksLocked=T
|RECORD=46|OwnerIndex=1044
|RECORD=48|OwnerIndex=1044
|RECORD=41|OwnerIndex=1046|IndexInSheet=-1|OwnerPartId=-1|Color=8388608|FontID=1|IsHidden=T|Text=2D|Name=Available Preview Images
|RECORD=45|OwnerIndex=1039|IndexInSheet=-1|Description=Chip Resistor, 2-Leads, Body 1.75x0.95mm, IPC High Density|UseComponentLibrary=T|ModelName=RESC1608X55X30LL15T15|ModelType=PCBLIB|DatafileCount=1|ModelDatafileEntity0=RESC1608X55X30LL15T15|ModelDatafileKind0=PCBLib|DatalinksLocked=T|DatabaseDatalinksLocked=T
|RECORD=46|OwnerIndex=1048
|RECORD=48|OwnerIndex=1048
|RECORD=41|OwnerIndex=1050|IndexInSheet=-1|OwnerPartId=-1|Color=8388608|FontID=1|IsHidden=T|Text=2D|Name=Available Preview Images
|RECORD=17|IndexInSheet=76|OwnerPartId=-1|ShowNetName=T|Location.X=1040|Location.Y=510|Orientation=1|Color=128|FontID=1|Text=+3.3V
|RECORD=17|IndexInSheet=77|OwnerPartId=-1|ShowNetName=T|Location.X=1070|Location.Y=510|Orientation=1|Color=128|FontID=1|Text=+3.3V
|RECORD=17|IndexInSheet=78|OwnerPartId=-1|ShowNetName=T|Location.X=1030|Location.Y=365|Orientation=2|Color=255|FontID=1|Text=ANT4_IN|IsCrossSheetConnector=T
|RECORD=1|LibReference=CAP|ComponentDescription=C0603X104K5RACAUTO|PartCount=2|DisplayModeCount=2|IndexInSheet=79|OwnerPartId=-1|Location.X=1110|Location.Y=320|Orientation=3|CurrentPartId=1|SourceLibraryName=Altium Content Vault|TargetFileName=*|AreaColor=11599871|Color=128|PartIDLocked=F|DesignItemId=CMP-2006-00003-1|AllPinCount=2
|RECORD=2|OwnerIndex=1055|OwnerPartId=1|OwnerPartDisplayMode=1|FormalType=1|Electrical=4|PinConglomerate=33|PinLength=10|Location.X=1100|Location.Y=320|Name=1|Designator=1|PinPropagationDelay=0.000000E+000
|RECORD=2|OwnerIndex=1055|OwnerPartId=1|OwnerPartDisplayMode=1|FormalType=1|Electrical=4|PinConglomerate=35|PinLength=10|Location.X=1100|Location.Y=310|Name=2|Designator=2|PinPropagationDelay=0.000000E+000
|RECORD=13|OwnerIndex=1055|IsNotAccesible=T|IndexInSheet=2|OwnerPartId=1|OwnerPartDisplayMode=1|Location.X=1092|Location.Y=320|Corner.X=1108|Corner.Y=320|LineWidth=1|Color=16711680
|RECORD=13|OwnerIndex=1055|IsNotAccesible=T|IndexInSheet=3|OwnerPartId=1|OwnerPartDisplayMode=1|Location.X=1100|Location.Y=316|Corner.X=1100|Corner.Y=310|LineWidth=1|Color=16711680
|RECORD=12|OwnerIndex=1055|IsNotAccesible=T|IndexInSheet=4|OwnerPartId=1|OwnerPartDisplayMode=1|Location.X=1100|Location.Y=300|Radius=16|LineWidth=1|StartAngle=61.000|EndAngle=90.000|Color=16711680
|RECORD=12|OwnerIndex=1055|IsNotAccesible=T|IndexInSheet=5|OwnerPartId=1|OwnerPartDisplayMode=1|Location.X=1100|Location.Y=300|Radius=16|LineWidth=1|StartAngle=90.000|EndAngle=119.000|Color=16711680
|RECORD=2|OwnerIndex=1055|OwnerPartId=1|FormalType=1|Electrical=4|PinConglomerate=33|PinLength=10|Location.X=1100|Location.Y=320|Name=1|Designator=1|PinPropagationDelay=0.000000E+000
|RECORD=2|OwnerIndex=1055|OwnerPartId=1|FormalType=1|Electrical=4|PinConglomerate=35|PinLength=10|Location.X=1100|Location.Y=310|Name=2|Designator=2|PinPropagationDelay=0.000000E+000
|RECORD=13|OwnerIndex=1055|IsNotAccesible=T|IndexInSheet=8|OwnerPartId=1|Location.X=1108|Location.Y=313|Corner.X=1092|Corner.Y=313|LineWidth=1|Color=16711680
|RECORD=13|OwnerIndex=1055|IsNotAccesible=T|IndexInSheet=9|OwnerPartId=1|Location.X=1092|Location.Y=317|Corner.X=1108|Corner.Y=317|LineWidth=1|Color=16711680
|RECORD=6|OwnerIndex=1055|IsNotAccesible=T|IndexInSheet=10|OwnerPartId=1|LineWidth=1|Color=16711680|LocationCount=2|X1=1100|Y1=320|X2=1100|Y2=317
|RECORD=6|OwnerIndex=1055|IsNotAccesible=T|IndexInSheet=11|OwnerPartId=1|LineWidth=1|Color=16711680|LocationCount=2|X1=1100|Y1=310|X2=1100|Y2=313
|RECORD=41|OwnerIndex=1055|IndexInSheet=12|OwnerPartId=-1|Location.X=1091|Location.Y=332|Color=8388608|FontID=1|IsHidden=T|Text=Kemet|Name=Manufacturer
|RECORD=41|OwnerIndex=1055|IndexInSheet=13|OwnerPartId=-1|Location.X=1091|Location.Y=332|Color=8388608|FontID=1|IsHidden=T|Text=C0603X104K5RACAUTO|Name=Part Number
|RECORD=34|OwnerIndex=1055|IndexInSheet=-1|OwnerPartId=-1|Location.X=1109|Location.Y=307|Color=8388608|FontID=1|Text=C29|Name=Designator|ReadOnlyState=1
|RECORD=41|OwnerIndex=1055|IndexInSheet=-1|OwnerPartId=-1|Location.X=1109|Location.Y=293|Color=8388608|FontID=1|Text=0.1uF|Name=Comment
|RECORD=44|OwnerIndex=1055
|RECORD=45|OwnerIndex=1076|IndexInSheet=-1|Description=Chip Capacitor, 2-Leads, Body 1.60x0.80mm, IPC Low Density|UseComponentLibrary=T|ModelName=CAPC1608X87X45ML20T05|ModelType=PCBLIB|DatafileCount=1|ModelDatafileEntity0=CAPC1608X87X45ML20T05|ModelDatafileKind0=PCBLib|IsCurrent=T|DatalinksLocked=T|DatabaseDatalinksLocked=T
|RECORD=46|OwnerIndex=1077
|RECORD=48|OwnerIndex=1077
|RECORD=41|OwnerIndex=1079|IndexInSheet=-1|OwnerPartId=-1|Color=8388608|FontID=1|Text=2D|Name=Available Preview Images
|RECORD=45|OwnerIndex=1076|IndexInSheet=-1|Description=Chip Capacitor, 2-Leads, Body 1.60x0.80mm, IPC High Density|UseComponentLibrary=T|ModelName=CAPC1608X87X45LL20T05|ModelType=PCBLIB|DatafileCount=1|ModelDatafileEntity0=CAPC1608X87X45LL20T05|ModelDatafileKind0=PCBLib|DatalinksLocked=T|DatabaseDatalinksLocked=T
|RECORD=46|OwnerIndex=1081
|RECORD=48|OwnerIndex=1081
|RECORD=41|OwnerIndex=1083|IndexInSheet=-1|OwnerPartId=-1|Color=8388608|FontID=1|Text=2D|Name=Available Preview Images
|RECORD=45|OwnerIndex=1076|IndexInSheet=-1|Description=Chip Capacitor, 2-Leads, Body 1.60x0.80mm, IPC Medium Density|UseComponentLibrary=T|ModelName=CAPC1608X87X45NL20T05|ModelType=PCBLIB|DatafileCount=1|ModelDatafileEntity0=CAPC1608X87X45NL20T05|ModelDatafileKind0=PCBLib|DatalinksLocked=T|DatabaseDatalinksLocked=T
|RECORD=46|OwnerIndex=1085
|RECORD=48|OwnerIndex=1085
|RECORD=41|OwnerIndex=1087|IndexInSheet=-1|OwnerPartId=-1|Color=8388608|FontID=1|Text=2D|Name=Available Preview Images
|RECORD=17|IndexInSheet=80|OwnerPartId=-1|Style=4|ShowNetName=T|Location.X=1150|Location.Y=290|Orientation=3|Color=128|FontID=1|Text=GND
|RECORD=17|IndexInSheet=81|OwnerPartId=-1|Style=4|ShowNetName=T|Location.X=1100|Location.Y=290|Orientation=3|Color=128|FontID=1|Text=GND
|RECORD=17|IndexInSheet=82|OwnerPartId=-1|ShowNetName=T|Location.X=1100|Location.Y=510|Orientation=1|Color=128|FontID=1|Text=+3.3V
|RECORD=1|LibReference=NC7WV125K8X|ComponentDescription=Integrated Circuit|PartCount=2|DisplayModeCount=1|IndexInSheet=83|OwnerPartId=-1|Location.X=400|Location.Y=355|CurrentPartId=1|LibraryPath=*|SourceLibraryName=SamacSys.SchLib|TargetFileName=*|AreaColor=11599871|Color=128|PartIDLocked=T|DesignItemId=NC7WV125K8X|AllPinCount=8
|RECORD=41|OwnerIndex=1092|OwnerPartId=-1|Location.X=400|Location.Y=355|Color=8388608|FontID=6|IsHidden=T|Text=https://www.mouser.com/datasheet/2/308/NC7WV125-1301459.pdf|Name=Datasheet Link
|RECORD=41|OwnerIndex=1092|IndexInSheet=1|OwnerPartId=-1|Location.X=400|Location.Y=355|Color=8388608|FontID=1|IsHidden=T|Text=0.9mm|Name=Height
|RECORD=41|OwnerIndex=1092|IndexInSheet=2|OwnerPartId=-1|Location.X=400|Location.Y=355|Color=8388608|FontID=1|IsHidden=T|Text=ON Semiconductor|Name=Manufacturer_Name
|RECORD=41|OwnerIndex=1092|IndexInSheet=3|OwnerPartId=-1|Location.X=400|Location.Y=355|Color=8388608|FontID=1|IsHidden=T|Text=NC7WV125K8X|Name=Manufacturer_Part_Number
|RECORD=41|OwnerIndex=1092|IndexInSheet=4|OwnerPartId=-1|Location.X=400|Location.Y=355|Color=8388608|FontID=1|IsHidden=T|Text=512-NC7WV125K8X|Name=Mouser Part Number
|RECORD=41|OwnerIndex=1092|IndexInSheet=5|OwnerPartId=-1|Location.X=400|Location.Y=355|Color=8388608|FontID=6|IsHidden=T|Text=https://www.mouser.com/Search/Refine.aspx?Keyword=512-NC7WV125K8X|Name=Mouser Price/Stock
|RECORD=41|OwnerIndex=1092|IndexInSheet=6|OwnerPartId=-1|Location.X=400|Location.Y=355|Color=8388608|FontID=1|IsHidden=T|Text=NC7WV125K8X|Name=Arrow Part Number
|RECORD=41|OwnerIndex=1092|IndexInSheet=7|OwnerPartId=-1|Location.X=400|Location.Y=355|Color=8388608|FontID=6|IsHidden=T|Text=https://www.arrow.com/en/products/nc7wv125k8x/on-semiconductor|Name=Arrow Price/Stock
|RECORD=14|OwnerIndex=1092|IsNotAccesible=T|IndexInSheet=8|OwnerPartId=1|Location.X=420|Location.Y=330|Corner.X=490|Corner.Y=455|LineWidth=1|Color=128|AreaColor=11599871|IsSolid=T
|RECORD=2|OwnerIndex=1092|OwnerPartId=1|FormalType=1|Electrical=4|PinConglomerate=58|PinLength=20|Location.X=420|Location.Y=445|Designator=1|SwapIDPart=Ž&Ž||PinPropagationDelay=0.000000E+000
|RECORD=2|OwnerIndex=1092|OwnerPartId=1|FormalType=1|Electrical=4|PinConglomerate=58|PinLength=20|Location.X=420|Location.Y=420|Designator=2|SwapIDPart=Ž&Ž||PinPropagationDelay=0.000000E+000
|RECORD=2|OwnerIndex=1092|OwnerPartId=1|FormalType=1|Electrical=4|PinConglomerate=58|PinLength=20|Location.X=420|Location.Y=365|Designator=3|SwapIDPart=Ž&Ž||PinPropagationDelay=0.000000E+000
|RECORD=2|OwnerIndex=1092|OwnerPartId=1|FormalType=1|Electrical=4|PinConglomerate=58|PinLength=20|Location.X=420|Location.Y=335|Name=GND|Designator=4|SwapIDPart=Ž&Ž||PinPropagationDelay=0.000000E+000
|RECORD=2|OwnerIndex=1092|OwnerPartId=1|FormalType=1|Electrical=4|PinConglomerate=58|PinLength=20|Location.X=420|Location.Y=345|Name=VCC|Designator=8|SwapIDPart=Ž&Ž||PinPropagationDelay=0.000000E+000
|RECORD=2|OwnerIndex=1092|OwnerPartId=1|FormalType=1|Electrical=4|PinConglomerate=58|PinLength=20|Location.X=420|Location.Y=390|Designator=7|SwapIDPart=Ž&Ž||PinPropagationDelay=0.000000E+000
|RECORD=2|OwnerIndex=1092|OwnerPartId=1|FormalType=1|Electrical=4|PinConglomerate=56|PinLength=20|Location.X=490|Location.Y=420|Designator=6|SwapIDPart=Ž&Ž||PinPropagationDelay=0.000000E+000
|RECORD=2|OwnerIndex=1092|OwnerPartId=1|FormalType=1|Electrical=4|PinConglomerate=56|PinLength=20|Location.X=490|Location.Y=365|Designator=5|SwapIDPart=Ž&Ž||PinPropagationDelay=0.000000E+000
|RECORD=6|OwnerIndex=1092|IsNotAccesible=T|IndexInSheet=17|OwnerPartId=1|LineWidth=1|Color=16711680|LocationCount=4|X1=445|Y1=430|X2=445|Y2=410|X3=465|Y3=420|X4=445|Y4=430
|RECORD=12|OwnerIndex=1092|IsNotAccesible=T|IndexInSheet=18|OwnerPartId=1|Location.X=455|Location.Y=427|Radius=1|Radius_Frac=79777|LineWidth=1|EndAngle=360.000|Color=16711680
|RECORD=6|OwnerIndex=1092|IsNotAccesible=T|IndexInSheet=19|OwnerPartId=1|LineWidth=1|Color=16711680|LocationCount=4|X1=465|Y1=375|X2=465|Y2=355|X3=445|Y3=365|X4=465|Y4=375
|RECORD=12|OwnerIndex=1092|IsNotAccesible=T|IndexInSheet=20|OwnerPartId=1|Location.X=455|Location.Y=372|Radius=1|Radius_Frac=79777|LineWidth=1|EndAngle=360.000|Color=16711680
|RECORD=6|OwnerIndex=1092|IsNotAccesible=T|IndexInSheet=21|OwnerPartId=1|LineWidth=1|Color=16711680|LocationCount=3|X1=455|Y1=374|X2=455|Y2=390|X3=420|Y3=390
|RECORD=6|OwnerIndex=1092|IsNotAccesible=T|IndexInSheet=22|OwnerPartId=1|LineWidth=1|Color=16711680|LocationCount=3|X1=455|Y1=429|X2=455|Y2=445|X3=420|Y3=445
|RECORD=6|OwnerIndex=1092|IsNotAccesible=T|IndexInSheet=23|OwnerPartId=1|LineWidth=1|Color=16711680|LocationCount=2|X1=420|Y1=420|X2=445|Y2=420
|RECORD=6|OwnerIndex=1092|IsNotAccesible=T|IndexInSheet=24|OwnerPartId=1|LineWidth=1|Color=16711680|LocationCount=2|X1=465|Y1=420|X2=490|Y2=420
|RECORD=6|OwnerIndex=1092|IsNotAccesible=T|IndexInSheet=25|OwnerPartId=1|LineWidth=1|Color=16711680|LocationCount=2|X1=465|Y1=365|X2=490|Y2=365
|RECORD=6|OwnerIndex=1092|IsNotAccesible=T|IndexInSheet=26|OwnerPartId=1|LineWidth=1|Color=16711680|LocationCount=2|X1=445|Y1=365|X2=420|Y2=365
|RECORD=34|OwnerIndex=1092|IndexInSheet=-1|OwnerPartId=-1|Location.X=419|Location.Y=455|Color=8388608|FontID=1|Text=U12|Name=Designator|ReadOnlyState=1
|RECORD=41|OwnerIndex=1092|IndexInSheet=-1|OwnerPartId=-1|Location.X=419|Location.Y=320|Color=8388608|FontID=1|Text=NC7WV125K8X|Name=Comment
|RECORD=44|OwnerIndex=1092
|RECORD=45|OwnerIndex=1130|IndexInSheet=-1|ModelName=SOP50P310X90-8N|ModelType=PCBLIB|DatafileCount=1|ModelDatafile0=C:\Users\<user>\Documents\AltiumLL\SamacSys.PcbLib|ModelDatafileEntity0=SOP50P310X90-8N|ModelDatafileKind0=PCBLIB|IsCurrent=T
|RECORD=46|OwnerIndex=1131
|RECORD=48|OwnerIndex=1131
|RECORD=17|IndexInSheet=84|OwnerPartId=-1|Style=4|ShowNetName=T|Location.X=710|Location.Y=290|Orientation=3|Color=128|FontID=1|Text=GND
|RECORD=1|LibReference=CN-1P-M-RF3|ComponentDescription=Ultra Miniature Coaxial Connector Jack, 60 V, 50 Ohm, -40 to 90 degC, RoHS, Tape and Reel|PartCount=2|DisplayModeCount=1|IndexInSheet=85|OwnerPartId=-1|Location.X=640|Location.Y=440|CurrentPartId=1|LibraryPath=*|SourceLibraryName=Altium Content Vault|TargetFileName=*|AreaColor=11599871|Color=128|PartIDLocked=T|DesignItemId=CMP-2000-07505-1|AllPinCount=3
|RECORD=8|OwnerIndex=1135|IsNotAccesible=T|OwnerPartId=1|Location.X=660|Location.Y=420|Radius=20|SecondaryRadius=20|LineWidth=1|Color=16711680|AreaColor=16777215
|RECORD=8|OwnerIndex=1135|IsNotAccesible=T|IndexInSheet=1|OwnerPartId=1|Location.X=660|Location.Y=420|Radius=4|SecondaryRadius=4|LineWidth=1|Color=16711680|AreaColor=16777215
|RECORD=2|OwnerIndex=1135|OwnerPartId=1|FormalType=1|Electrical=4|PinConglomerate=51|PinLength=10|Location.X=650|Location.Y=400|Name=1|Designator=1|PinPropagationDelay=0.000000E+000
|RECORD=2|OwnerIndex=1135|OwnerPartId=1|FormalType=1|Electrical=4|PinConglomerate=50|PinLength=10|Location.X=640|Location.Y=420|Name=2|Designator=2|PinPropagationDelay=0.000000E+000
|RECORD=2|OwnerIndex=1135|OwnerPartId=1|FormalType=1|Electrical=4|PinConglomerate=51|PinLength=10|Location.X=670|Location.Y=400|Name=3|Designator=3|PinPropagationDelay=0.000000E+000
|RECORD=6|OwnerIndex=1135|IsNotAccesible=T|IndexInSheet=5|OwnerPartId=1|LineWidth=1|Color=16711680|LocationCount=5|X1=640|Y1=400|X2=640|Y2=440|X3=680|Y3=440|X4=680|Y4=400|X5=640|Y5=400
|RECORD=6|OwnerIndex=1135|IsNotAccesible=T|IndexInSheet=6|OwnerPartId=1|LineWidth=1|Color=16711680|LocationCount=2|X1=640|Y1=420|X2=656|Y2=420
|RECORD=41|OwnerIndex=1135|IndexInSheet=7|OwnerPartId=-1|Location.X=628|Location.Y=441|Color=8388608|FontID=1|IsHidden=T|Text=Straight|Name=Orientation
|RECORD=41|OwnerIndex=1135|IndexInSheet=8|OwnerPartId=-1|Location.X=628|Location.Y=441|Color=8388608|FontID=1|IsHidden=T|Text=Female|Name=Gender
|RECORD=41|OwnerIndex=1135|IndexInSheet=9|OwnerPartId=-1|Location.X=628|Location.Y=441|Color=8388608|FontID=1|IsHidden=T|Text=Vertical|Name=PCB Mounting Orientation
|RECORD=41|OwnerIndex=1135|IndexInSheet=10|OwnerPartId=-1|Location.X=628|Location.Y=441|Color=8388608|FontID=1|IsHidden=T|Text=SurfaceMount|Name=Mount
|RECORD=41|OwnerIndex=1135|IndexInSheet=11|OwnerPartId=-1|Location.X=628|Location.Y=441|Color=8388608|FontID=1|IsHidden=T|Text=3mm|Name=Length
|RECORD=41|OwnerIndex=1135|IndexInSheet=12|OwnerPartId=-1|Location.X=628|Location.Y=441|Color=8388608|FontID=1|IsHidden=T|Text=TapeandReel|Name=Packaging
|RECORD=41|OwnerIndex=1135|IndexInSheet=13|OwnerPartId=-1|Location.X=628|Location.Y=441|Color=8388608|FontID=1|IsHidden=T|Text=Jack|Name=Connector Type
|RECORD=41|OwnerIndex=1135|IndexInSheet=14|OwnerPartId=-1|Location.X=628|Location.Y=441|Color=8388608|FontID=1|IsHidden=T|Text=LeadFree|Name=Lead Free
|RECORD=41|OwnerIndex=1135|IndexInSheet=15|OwnerPartId=-1|Location.X=628|Location.Y=441|Color=8388608|FontID=1|IsHidden=T|Text=1|Name=Package Quantity
|RECORD=41|OwnerIndex=1135|IndexInSheet=16|OwnerPartId=-1|Location.X=628|Location.Y=441|Color=8388608|FontID=1|IsHidden=T|Text=SMD/SMT|Name=Termination
|RECORD=41|OwnerIndex=1135|IndexInSheet=17|OwnerPartId=-1|Location.X=628|Location.Y=441|Color=8388608|FontID=1|IsHidden=T|Text=CopperAlloy|Name=Contact Material
|RECORD=41|OwnerIndex=1135|IndexInSheet=18|OwnerPartId=-1|Location.X=628|Location.Y=441|Color=8388608|FontID=1|IsHidden=T|Text=Pull|Name=Fastening Type
|RECORD=41|OwnerIndex=1135|IndexInSheet=19|OwnerPartId=-1|Location.X=628|Location.Y=441|Color=8388608|FontID=1|IsHidden=T|Text=true|Name=RoHSCompliant
|RECORD=41|OwnerIndex=1135|IndexInSheet=20|OwnerPartId=-1|Location.X=628|Location.Y=441|Color=8388608|FontID=1|IsHidden=T|Text=LiquidCrystalPolymer|Name=Body Material
|RECORD=41|OwnerIndex=1135|IndexInSheet=21|OwnerPartId=-1|Location.X=628|Location.Y=441|Color=8388608|FontID=1|IsHidden=T|Text=SMD/SMT|Name=Case\/Package
|RECORD=41|OwnerIndex=1135|IndexInSheet=22|OwnerPartId=-1|Location.X=628|Location.Y=441|Color=8388608|FontID=1|IsHidden=T|Text=90degC|Name=Max Operating Temperature
|RECORD=41|OwnerIndex=1135|IndexInSheet=23|OwnerPartId=-1|Location.X=628|Location.Y=441|Color=8388608|FontID=1|IsHidden=T|Text=50Ohm|Name=Impedance
|RECORD=41|OwnerIndex=1135|IndexInSheet=24|OwnerPartId=-1|Location.X=628|Location.Y=441|Color=8388608|FontID=6|IsHidden=T|Text=http://www.te.com/commerce/DocumentDelivery/DDEController?Action=srchrtrv&DocNm=1909763&DocType=Customer+Drawing&DocLang=English|Name=Datasheet URL
|RECORD=41|OwnerIndex=1135|IndexInSheet=25|OwnerPartId=-1|Location.X=628|Location.Y=441|Color=8388608|FontID=1|IsHidden=T|Text=Gold|Name=Contact Plating
|RECORD=41|OwnerIndex=1135|IndexInSheet=26|OwnerPartId=-1|Location.X=628|Location.Y=441|Color=8388608|FontID=1|IsHidden=T|Text=SurfaceMount|Name=Mounting Technology
|RECORD=41|OwnerIndex=1135|IndexInSheet=27|OwnerPartId=-1|Location.X=628|Location.Y=441|Color=8388608|FontID=1|IsHidden=T|Text=6GHz|Name=Max Frequency
|RECORD=41|OwnerIndex=1135|IndexInSheet=28|OwnerPartId=-1|Location.X=628|Location.Y=441|Color=8388608|FontID=1|IsHidden=T|Text=TECO-1909763-1|Name=Package Reference
|RECORD=41|OwnerIndex=1135|IndexInSheet=29|OwnerPartId=-1|Location.X=628|Location.Y=441|Color=8388608|FontID=1|IsHidden=T|Text=Thermoplastic|Name=Insulation Material
|RECORD=41|OwnerIndex=1135|IndexInSheet=30|OwnerPartId=-1|Location.X=628|Location.Y=441|Color=8388608|FontID=1|IsHidden=T|Text=-40degC|Name=Min Operating Temperature
|RECORD=41|OwnerIndex=1135|IndexInSheet=31|OwnerPartId=-1|Location.X=628|Location.Y=441|Color=8388608|FontID=6|IsHidden=T|Text=http://www.te.com/|Name=Manufacturer URL
|RECORD=41|OwnerIndex=1135|IndexInSheet=32|OwnerPartId=-1|Location.X=628|Location.Y=441|Color=8388608|FontID=1|IsHidden=T|Text=Gold|Name=Body Plating
|RECORD=41|OwnerIndex=1135|IndexInSheet=33|OwnerPartId=-1|Location.X=628|Location.Y=441|Color=8388608|FontID=1|IsHidden=T|Text=Polymer|Name=Dielectric Material
|RECORD=41|OwnerIndex=1135|IndexInSheet=34|OwnerPartId=-1|Location.X=628|Location.Y=441|Color=8388608|FontID=1|IsHidden=T|Text=TE Connectivity|Name=Manufacturer
|RECORD=41|OwnerIndex=1135|IndexInSheet=35|OwnerPartId=-1|Location.X=628|Location.Y=441|Color=8388608|FontID=1|IsHidden=T|Text=Compliant|Name=ELV
|RECORD=41|OwnerIndex=1135|IndexInSheet=36|OwnerPartId=-1|Location.X=628|Location.Y=441|Color=8388608|FontID=1|IsHidden=T|Text=Rev. B2, 11/2015|Name=Datasheet Version
|RECORD=41|OwnerIndex=1135|IndexInSheet=37|OwnerPartId=-1|Location.X=628|Location.Y=441|Color=8388608|FontID=1|IsHidden=T|Text=No|Name=Radiation Hardening
|RECORD=41|OwnerIndex=1135|IndexInSheet=38|OwnerPartId=-1|Location.X=628|Location.Y=441|Color=8388608|FontID=1|IsHidden=T|Text=3-Pin Surface Mount Device, Body 2.6 x 2.6 mm|Name=Package Description
|RECORD=41|OwnerIndex=1135|IndexInSheet=39|OwnerPartId=-1|Location.X=628|Location.Y=441|Color=8388608|FontID=1|IsHidden=T|Text=Beige|Name=Housing Colour
|RECORD=34|OwnerIndex=1135|IndexInSheet=-1|OwnerPartId=-1|Location.X=639|Location.Y=441|Color=8388608|FontID=1|Text=J2|Name=Designator|ReadOnlyState=1
|RECORD=41|OwnerIndex=1135|IndexInSheet=-1|OwnerPartId=-1|Location.X=690|Location.Y=400|Color=8388608|FontID=1|Text=1909763-1|Name=Comment
|RECORD=44|OwnerIndex=1135
|RECORD=45|OwnerIndex=1181|IndexInSheet=-1|Description=SMD, 3-Leads, Body 2.6x2.6mm, Height 1.25mm|UseComponentLibrary=T|ModelName=TECO-1909763-1_V|ModelType=PCBLIB|DatafileCount=1|ModelDatafileEntity0=TECO-1909763-1_V|ModelDatafileKind0=PCBLib|IsCurrent=T|DatalinksLocked=T|DatabaseDatalinksLocked=T
|RECORD=46|OwnerIndex=1182
|RECORD=48|OwnerIndex=1182
|RECORD=41|OwnerIndex=1184|IndexInSheet=-1|OwnerPartId=-1|Color=8388608|FontID=1|Text=2D|Name=Available Preview Images
|RECORD=1|LibReference=CN-S-4F-RF5|ComponentDescription=Coaxial connector, 50 Ohm, -65 to 165 degC, 5-Pin THD, RoHS, Bulk|PartCount=2|DisplayModeCount=1|IndexInSheet=86|OwnerPartId=-1|Location.X=640|Location.Y=360|CurrentPartId=1|LibraryPath=*|SourceLibraryName=Altium Content Vault|TargetFileName=*|AreaColor=11599871|Color=128|PartIDLocked=T|DesignItemId=CMP-2000-05705-1|AllPinCount=5
|RECORD=2|OwnerIndex=1186|OwnerPartId=1|FormalType=1|Electrical=4|PinConglomerate=51|PinLength=10|Location.X=680|Location.Y=320|Name=5|Designator=5|SwapIDPart=Ž&Ž1|PinPropagationDelay=0.000000E+000
|RECORD=8|OwnerIndex=1186|IsNotAccesible=T|IndexInSheet=1|OwnerPartId=1|Location.X=660|Location.Y=340|Radius=20|SecondaryRadius=20|LineWidth=1|Color=16711680|AreaColor=16777215
|RECORD=8|OwnerIndex=1186|IsNotAccesible=T|IndexInSheet=2|OwnerPartId=1|Location.X=660|Location.Y=340|Radius=4|SecondaryRadius=4|LineWidth=1|Color=16711680|AreaColor=16777215
|RECORD=2|OwnerIndex=1186|OwnerPartId=1|FormalType=1|Electrical=4|PinConglomerate=50|PinLength=10|Location.X=640|Location.Y=340|Name=1|Designator=1|PinPropagationDelay=0.000000E+000
|RECORD=2|OwnerIndex=1186|OwnerPartId=1|FormalType=1|Electrical=4|PinConglomerate=51|PinLength=10|Location.X=650|Location.Y=320|Name=2|Designator=2|PinPropagationDelay=0.000000E+000
|RECORD=2|OwnerIndex=1186|OwnerPartId=1|FormalType=1|Electrical=4|PinConglomerate=51|PinLength=10|Location.X=660|Location.Y=320|Name=3|Designator=3|PinPropagationDelay=0.000000E+000
|RECORD=2|OwnerIndex=1186|OwnerPartId=1|FormalType=1|Electrical=4|PinConglomerate=51|PinLength=10|Location.X=670|Location.Y=320|Name=4|Designator=4|PinPropagationDelay=0.000000E+000
|RECORD=6|OwnerIndex=1186|IsNotAccesible=T|IndexInSheet=7|OwnerPartId=1|LineWidth=1|Color=16711680|LocationCount=5|X1=640|Y1=320|X2=640|Y2=360|X3=680|Y3=360|X4=680|Y4=320|X5=640|Y5=320
|RECORD=6|OwnerIndex=1186|IsNotAccesible=T|IndexInSheet=8|OwnerPartId=1|LineWidth=1|Color=16711680|LocationCount=2|X1=640|Y1=340|X2=656|Y2=340
|RECORD=41|OwnerIndex=1186|IndexInSheet=9|OwnerPartId=-1|Location.X=628|Location.Y=361|Color=8388608|FontID=1|IsHidden=T|Text=ThroughHole|Name=Mounting Technology
|RECORD=41|OwnerIndex=1186|IndexInSheet=10|OwnerPartId=-1|Location.X=628|Location.Y=361|Color=8388608|FontID=1|IsHidden=T|Text=ThroughHole,RightAngle|Name=Mounting Type
|RECORD=41|OwnerIndex=1186|IndexInSheet=11|OwnerPartId=-1|Location.X=628|Location.Y=361|Color=8388608|FontID=1|IsHidden=T|Text=-|Name=Cable Group
|RECORD=41|OwnerIndex=1186|IndexInSheet=12|OwnerPartId=-1|Location.X=628|Location.Y=361|Color=8388608|FontID=1|IsHidden=T|Text=901-143-6RFXMountingHole|Name=Catalog Drawings
|RECORD=41|OwnerIndex=1186|IndexInSheet=13|OwnerPartId=-1|Location.X=628|Location.Y=361|Color=8388608|FontID=1|IsHidden=T|Text=901-143-6RFX.igs|Name=3D Model
|RECORD=41|OwnerIndex=1186|IndexInSheet=14|OwnerPartId=-1|Location.X=628|Location.Y=361|Color=8388608|FontID=1|IsHidden=T|Text=-|Name=Series
|RECORD=41|OwnerIndex=1186|IndexInSheet=15|OwnerPartId=-1|Location.X=628|Location.Y=361|Color=8388608|FontID=1|IsHidden=T|Text=5-Pin Through Hole Device, Body 7 x 7 mm, Pitch 2.54 mm|Name=Package Description
|RECORD=41|OwnerIndex=1186|IndexInSheet=16|OwnerPartId=-1|Location.X=628|Location.Y=361|Color=8388608|FontID=1|IsHidden=T|Text=901-143-6RFX|Name=Package Reference
|RECORD=41|OwnerIndex=1186|IndexInSheet=17|OwnerPartId=-1|Location.X=628|Location.Y=361|Color=8388608|FontID=1|IsHidden=T|Text=Brass|Name=Body Material
|RECORD=41|OwnerIndex=1186|IndexInSheet=18|OwnerPartId=-1|Location.X=628|Location.Y=361|Color=8388608|FontID=1|IsHidden=T|Text=-|Name=Voltage Rating
|RECORD=41|OwnerIndex=1186|IndexInSheet=19|OwnerPartId=-1|Location.X=628|Location.Y=361|Color=8388608|FontID=1|IsHidden=T|Text=1|Name=Standard Package
|RECORD=41|OwnerIndex=1186|IndexInSheet=20|OwnerPartId=-1|Location.X=628|Location.Y=361|Color=8388608|FontID=1|IsHidden=T|Text=Jack,FemaleSocket|Name=Connector Type
|RECORD=41|OwnerIndex=1186|IndexInSheet=21|OwnerPartId=-1|Location.X=628|Location.Y=361|Color=8388608|FontID=1|IsHidden=T|Text=Threaded|Name=Fastening Type
|RECORD=41|OwnerIndex=1186|IndexInSheet=22|OwnerPartId=-1|Location.X=628|Location.Y=361|Color=8388608|FontID=1|IsHidden=T|Text=Gold|Name=Housing Color
|RECORD=41|OwnerIndex=1186|IndexInSheet=23|OwnerPartId=-1|Location.X=628|Location.Y=361|Color=8388608|FontID=1|IsHidden=T|Text=Solder|Name=Shield Termination
|RECORD=41|OwnerIndex=1186|IndexInSheet=24|OwnerPartId=-1|Location.X=628|Location.Y=361|Color=8388608|FontID=1|IsHidden=T|Text=901-143-6-RFX9011436RFXARFX1232|Name=Other Names
|RECORD=41|OwnerIndex=1186|IndexInSheet=25|OwnerPartId=-1|Location.X=628|Location.Y=361|Color=8388608|FontID=6|IsHidden=T|Text=http://www.amphenolrf.com/downloads/dl/file/id/2712/product/3102/901_143_6rfx_customer_drawing.pdf|Name=Datasheet URL
|RECORD=41|OwnerIndex=1186|IndexInSheet=26|OwnerPartId=-1|Location.X=628|Location.Y=361|Color=8388608|FontID=1|IsHidden=T|Text=CoaxialConnectors(RF)|Name=Family
|RECORD=41|OwnerIndex=1186|IndexInSheet=27|OwnerPartId=-1|Location.X=628|Location.Y=361|Color=8388608|FontID=1|IsHidden=T|Text=SMA,RFX|Name=Online Catalog
|RECORD=41|OwnerIndex=1186|IndexInSheet=28|OwnerPartId=-1|Location.X=628|Location.Y=361|Color=8388608|FontID=1|IsHidden=T|Text=18GHz|Name=Frequency - Max
|RECORD=41|OwnerIndex=1186|IndexInSheet=29|OwnerPartId=-1|Location.X=628|Location.Y=361|Color=8388608|FontID=1|IsHidden=T|Text=Solder|Name=Contact Termination
|RECORD=41|OwnerIndex=1186|IndexInSheet=30|OwnerPartId=-1|Location.X=628|Location.Y=361|Color=8388608|FontID=6|IsHidden=T|Text=http://www.amphenol.com/|Name=Manufacturer URL
|RECORD=41|OwnerIndex=1186|IndexInSheet=31|OwnerPartId=-1|Location.X=628|Location.Y=361|Color=8388608|FontID=1|IsHidden=T|Text=Amphenol|Name=Manufacturer
|RECORD=41|OwnerIndex=1186|IndexInSheet=32|OwnerPartId=-1|Location.X=628|Location.Y=361|Color=8388608|FontID=1|IsHidden=T|Text=-65°C~165°C|Name=Operating Temperature
|RECORD=41|OwnerIndex=1186|IndexInSheet=33|OwnerPartId=-1|Location.X=628|Location.Y=361|Color=8388608|FontID=1|IsHidden=T|Text=Connectors,Interconnects|Name=Category
|RECORD=41|OwnerIndex=1186|IndexInSheet=34|OwnerPartId=-1|Location.X=628|Location.Y=361|Color=8388608|FontID=1|IsHidden=T|Text=Bulk|Name=Packaging
|RECORD=41|OwnerIndex=1186|IndexInSheet=35|OwnerPartId=-1|Location.X=628|Location.Y=361|Color=8388608|FontID=1|IsHidden=T|Text=Gold|Name=Body Finish
|RECORD=41|OwnerIndex=1186|IndexInSheet=36|OwnerPartId=-1|Location.X=628|Location.Y=361|Color=8388608|FontID=1|IsHidden=T|Text=Polytetrafluoroethylene(PTFE)|Name=Dielectric Material
|RECORD=41|OwnerIndex=1186|IndexInSheet=37|OwnerPartId=-1|Location.X=628|Location.Y=361|Color=8388608|FontID=1|IsHidden=T|Text=BerylliumCopper|Name=Center Contact Material
|RECORD=41|OwnerIndex=1186|IndexInSheet=38|OwnerPartId=-1|Location.X=628|Location.Y=361|Color=8388608|FontID=1|IsHidden=T|Text=50Ohm|Name=Impedance
|RECORD=41|OwnerIndex=1186|IndexInSheet=39|OwnerPartId=-1|Location.X=628|Location.Y=361|Color=8388608|FontID=1|IsHidden=T|Text=-|Name=Features
|RECORD=41|OwnerIndex=1186|IndexInSheet=40|OwnerPartId=-1|Location.X=628|Location.Y=361|Color=8388608|FontID=1|IsHidden=T|Text=SMA|Name=Connector Style
|RECORD=41|OwnerIndex=1186|IndexInSheet=41|OwnerPartId=-1|Location.X=628|Location.Y=361|Color=8388608|FontID=1|IsHidden=T|Text=Gold|Name=Center Contact Plating
|RECORD=41|OwnerIndex=1186|IndexInSheet=42|OwnerPartId=-1|Location.X=628|Location.Y=361|Color=8388608|FontID=1|IsHidden=T|Text=Rev. C, 06/2010|Name=Datasheet Version
|RECORD=41|OwnerIndex=1186|IndexInSheet=43|OwnerPartId=-1|Location.X=628|Location.Y=361|Color=8388608|FontID=1|IsHidden=T|Text=-|Name=Ingress Protection
|RECORD=34|OwnerIndex=1186|IndexInSheet=-1|OwnerPartId=-1|Location.X=639|Location.Y=361|Color=8388608|FontID=1|Text=AN2|Name=Designator|ReadOnlyState=1
|RECORD=41|OwnerIndex=1186|IndexInSheet=-1|OwnerPartId=-1|Location.X=690|Location.Y=310|Color=8388608|FontID=1|Text=901-143-6RFX|Name=Comment
|RECORD=44|OwnerIndex=1186
|RECORD=45|OwnerIndex=1238|IndexInSheet=-1|Description=THD, 5-Leads, Body 7x7mm, Pitch 2.54mm|UseComponentLibrary=T|ModelName=AMPH-901-143-6RFX_V|ModelType=PCBLIB|DatafileCount=1|ModelDatafileEntity0=AMPH-901-143-6RFX_V|ModelDatafileKind0=PCBLib|IsCurrent=T|DatalinksLocked=T|DatabaseDatalinksLocked=T
|RECORD=46|OwnerIndex=1239
|RECORD=48|OwnerIndex=1239
|RECORD=41|OwnerIndex=1241|IndexInSheet=-1|OwnerPartId=-1|Color=8388608|FontID=1|Text=2D|Name=Available Preview Images
|RECORD=17|IndexInSheet=87|OwnerPartId=-1|Style=4|ShowNetName=T|Location.X=710|Location.Y=380|Orientation=3|Color=128|FontID=1|Text=GND
|RECORD=1|LibReference=RES-2|ComponentDescription=General Purpose Chip Resistor, 49.9 Ohm, +/- 1%, -55 to 155 degC, 0603 (1608 Metric), RoHS, Tape and Reel|PartCount=2|DisplayModeCount=1|IndexInSheet=88|OwnerPartId=-1|Location.X=545|Location.Y=420|CurrentPartId=1|LibraryPath=*|SourceLibraryName=Altium Content Vault|TargetFileName=*|AreaColor=11599871|Color=128|PartIDLocked=T|DesignItemId=CMP-1659-00036-1|AllPinCount=2
|RECORD=2|OwnerIndex=1244|OwnerPartId=1|FormalType=1|Electrical=4|PinConglomerate=32|PinLength=10|Location.X=565|Location.Y=420|Name=2|Designator=2|PinPropagationDelay=0.000000E+000
|RECORD=2|OwnerIndex=1244|OwnerPartId=1|FormalType=1|Electrical=4|PinConglomerate=34|PinLength=10|Location.X=545|Location.Y=420|Name=1|Designator=1|PinPropagationDelay=0.000000E+000
|RECORD=6|OwnerIndex=1244|IsNotAccesible=T|IndexInSheet=2|OwnerPartId=1|LineWidth=1|Color=16711680|LocationCount=10|X1=565|Y1=420|X2=561|Y2=420|X3=560|Y3=418|X4=558|Y4=422|X5=556|Y5=418|X6=554|Y6=422|X7=552|Y7=418|X8=550|Y8=422|X9=549|Y9=420|X10=545|Y10=420
|RECORD=41|OwnerIndex=1244|IndexInSheet=3|OwnerPartId=-1|Location.X=533|Location.Y=435|Color=8388608|FontID=1|IsHidden=T|Text=0603|Name=PackageReference
|RECORD=41|OwnerIndex=1244|IndexInSheet=4|OwnerPartId=-1|Location.X=533|Location.Y=435|Color=8388608|FontID=1|IsHidden=T|Text=Tray|Name=Packaging
|RECORD=41|OwnerIndex=1244|IndexInSheet=5|OwnerPartId=-1|Location.X=533|Location.Y=435|Color=8388608|FontID=1|IsHidden=T|Text=Datasheet|Name=ComponentLink2Description
|RECORD=41|OwnerIndex=1244|IndexInSheet=6|OwnerPartId=-1|Location.X=533|Location.Y=435|Color=8388608|FontID=1|IsHidden=T|Text=Manufacturer URL|Name=ComponentLink1Description
|RECORD=41|OwnerIndex=1244|IndexInSheet=7|OwnerPartId=-1|Location.X=533|Location.Y=435|Color=8388608|FontID=6|IsHidden=T|Text=https://datasheet.ciiva.com/11808/0900766b80f96399-11808223.pdf|Name=ComponentLink2URL
|RECORD=41|OwnerIndex=1244|IndexInSheet=8|OwnerPartId=-1|Location.X=533|Location.Y=435|Color=8388608|FontID=1|IsHidden=T|Text=true|Name=RoHSCompliant
|RECORD=41|OwnerIndex=1244|IndexInSheet=9|OwnerPartId=-1|Location.X=533|Location.Y=435|Color=8388608|FontID=1|IsHidden=T|Text=85 degC|Name=Max Operating Temperature
|RECORD=41|OwnerIndex=1244|IndexInSheet=10|OwnerPartId=-1|Location.X=533|Location.Y=435|Color=8388608|FontID=1|IsHidden=T|Text=3.63 V|Name=Max Supply Voltage
|RECORD=41|OwnerIndex=1244|IndexInSheet=11|OwnerPartId=-1|Location.X=533|Location.Y=435|Color=8388608|FontID=6|IsHidden=T|Text=http://www.yageo.com/|Name=ComponentLink1URL
|RECORD=41|OwnerIndex=1244|IndexInSheet=12|OwnerPartId=-1|Location.X=533|Location.Y=435|Color=8388608|FontID=1|IsHidden=T|Text=2-Pin Surface Mount Device, Body 1.6 x 0.8 mm|Name=PackageDescription
|RECORD=41|OwnerIndex=1244|IndexInSheet=13|OwnerPartId=-1|Location.X=533|Location.Y=435|Color=8388608|FontID=1|IsHidden=T|Text=LQFP|Name=Case\Package
|RECORD=41|OwnerIndex=1244|IndexInSheet=14|OwnerPartId=-1|Location.X=533|Location.Y=435|Color=8388608|FontID=1|IsHidden=T|Text=Rev. 4, 04/2009|Name=DatasheetVersion
|RECORD=41|OwnerIndex=1244|IndexInSheet=15|OwnerPartId=-1|Location.X=533|Location.Y=435|Color=8388608|FontID=1|IsHidden=T|Text=-40 degC|Name=Min Operating Temperature
|RECORD=41|OwnerIndex=1244|IndexInSheet=16|OwnerPartId=-1|Location.X=533|Location.Y=435|Color=8388608|FontID=1|IsHidden=T|Text=SPI|Name=Interface
|RECORD=41|OwnerIndex=1244|IndexInSheet=17|OwnerPartId=-1|Location.X=533|Location.Y=435|Color=8388608|FontID=1|IsHidden=T|Text=250|Name=Package Quantity
|RECORD=41|OwnerIndex=1244|IndexInSheet=18|OwnerPartId=-1|Location.X=533|Location.Y=435|Color=8388608|FontID=1|IsHidden=T|Text=2.97 V|Name=Min Supply Voltage
|RECORD=41|OwnerIndex=1244|IndexInSheet=19|OwnerPartId=-1|Location.X=533|Location.Y=435|Color=8388608|FontID=1|IsHidden=T|Text=48|Name=Pins
|RECORD=34|OwnerIndex=1244|IndexInSheet=-1|OwnerPartId=-1|Location.X=544|Location.Y=423|Color=8388608|FontID=1|Text=R33|Name=Designator|ReadOnlyState=1
|RECORD=41|OwnerIndex=1244|IndexInSheet=-1|OwnerPartId=-1|Location.X=544|Location.Y=407|Color=8388608|FontID=1|Text=49.9R|Name=Comment
|RECORD=44|OwnerIndex=1244
|RECORD=45|OwnerIndex=1269|IndexInSheet=-1|Description=Chip Resistor, 2-Leads, Body 1.70x0.90mm, IPC Medium Density|UseComponentLibrary=T|ModelName=RESC1608X55X25NL10T15|ModelType=PCBLIB|DatafileCount=1|ModelDatafileEntity0=RESC1608X55X25NL10T15|ModelDatafileKind0=PCBLib|IsCurrent=T|DatalinksLocked=T|DatabaseDatalinksLocked=T
|RECORD=46|OwnerIndex=1270
|RECORD=48|OwnerIndex=1270
|RECORD=41|OwnerIndex=1272|IndexInSheet=-1|OwnerPartId=-1|Color=8388608|FontID=1|IsHidden=T|Text=2D|Name=Available Preview Images
|RECORD=45|OwnerIndex=1269|IndexInSheet=-1|Description=Chip Resistor, 2-Leads, Body 1.70x0.90mm, IPC Low Density|UseComponentLibrary=T|ModelName=RESC1608X55X25ML10T15|ModelType=PCBLIB|DatafileCount=1|ModelDatafileEntity0=RESC1608X55X25ML10T15|ModelDatafileKind0=PCBLib|DatalinksLocked=T|DatabaseDatalinksLocked=T
|RECORD=46|OwnerIndex=1274
|RECORD=48|OwnerIndex=1274
|RECORD=41|OwnerIndex=1276|IndexInSheet=-1|OwnerPartId=-1|Color=8388608|FontID=1|IsHidden=T|Text=2D|Name=Available Preview Images
|RECORD=45|OwnerIndex=1269|IndexInSheet=-1|Description=Chip Resistor, 2-Leads, Body 1.70x0.90mm, IPC High Density|UseComponentLibrary=T|ModelName=RESC1608X55X25LL10T15|ModelType=PCBLIB|DatafileCount=1|ModelDatafileEntity0=RESC1608X55X25LL10T15|ModelDatafileKind0=PCBLib|DatalinksLocked=T|DatabaseDatalinksLocked=T
|RECORD=46|OwnerIndex=1278
|RECORD=48|OwnerIndex=1278
|RECORD=41|OwnerIndex=1280|IndexInSheet=-1|OwnerPartId=-1|Color=8388608|FontID=1|IsHidden=T|Text=2D|Name=Available Preview Images
|RECORD=17|IndexInSheet=89|OwnerPartId=-1|ShowNetName=T|Location.X=270|Location.Y=420|Orientation=2|Color=255|FontID=1|Text=ANT2_OUT|IsCrossSheetConnector=T
|RECORD=1|LibReference=RES-2|ComponentDescription=Precision Thick Film Chip Resistor, 4.7 KOhm, +/- 1%, -55 to 155 degC, 0603 (1608 Metric), RoHS, Tape and Reel ERJ-3EKF4701V|PartCount=2|DisplayModeCount=1|IndexInSheet=90|OwnerPartId=-1|Location.X=280|Location.Y=480|Orientation=1|CurrentPartId=1|LibraryPath=*|SourceLibraryName=Altium Content Vault|TargetFileName=*|AreaColor=11599871|Color=128|PartIDLocked=T|DesignItemId=CMP-1012-00586-3|AllPinCount=2
|RECORD=2|OwnerIndex=1283|OwnerPartId=1|FormalType=1|Electrical=4|PinConglomerate=33|PinLength=10|Location.X=280|Location.Y=500|Name=2|Designator=2|PinPropagationDelay=0.000000E+000
|RECORD=2|OwnerIndex=1283|OwnerPartId=1|FormalType=1|Electrical=4|PinConglomerate=35|PinLength=10|Location.X=280|Location.Y=480|Name=1|Designator=1|PinPropagationDelay=0.000000E+000
|RECORD=6|OwnerIndex=1283|IsNotAccesible=T|IndexInSheet=2|OwnerPartId=1|LineWidth=1|Color=16711680|LocationCount=10|X1=280|Y1=500|X2=280|Y2=496|X3=282|Y3=495|X4=278|Y4=493|X5=282|Y5=491|X6=278|Y6=489|X7=282|Y7=487|X8=278|Y8=485|X9=280|Y9=484|X10=280|Y10=480
|RECORD=41|OwnerIndex=1283|IndexInSheet=3|OwnerPartId=-1|Location.X=277|Location.Y=512|Color=8388608|FontID=1|IsHidden=T|Text=220 Ohm|Name=Resistance
|RECORD=41|OwnerIndex=1283|IndexInSheet=4|OwnerPartId=-1|Location.X=277|Location.Y=512|Color=8388608|FontID=1|IsHidden=T|Text=0603|Name=PackageReference
|RECORD=41|OwnerIndex=1283|IndexInSheet=5|OwnerPartId=-1|Location.X=277|Location.Y=512|Color=8388608|FontID=1|IsHidden=T|Text=50 V|Name=Voltage Rating
|RECORD=41|OwnerIndex=1283|IndexInSheet=6|OwnerPartId=-1|Location.X=277|Location.Y=512|Color=8388608|FontID=1|IsHidden=T|Text=125 degC|Name=Max Operating Temperature
|RECORD=41|OwnerIndex=1283|IndexInSheet=7|OwnerPartId=-1|Location.X=277|Location.Y=512|Color=8388608|FontID=1|IsHidden=T|Text=4|Name=Elements
|RECORD=41|OwnerIndex=1283|IndexInSheet=8|OwnerPartId=-1|Location.X=277|Location.Y=512|Color=8388608|FontID=1|IsHidden=T|Text=No SVHC|Name=REACH SVHC
|RECORD=41|OwnerIndex=1283|IndexInSheet=9|OwnerPartId=-1|Location.X=277|Location.Y=512|Color=8388608|FontID=1|IsHidden=T|Text=0.063 inch|Name=Width
|RECORD=41|OwnerIndex=1283|IndexInSheet=10|OwnerPartId=-1|Location.X=277|Location.Y=512|Color=8388608|FontID=1|IsHidden=T|Text=1205|Name=Case\Package
|RECORD=41|OwnerIndex=1283|IndexInSheet=11|OwnerPartId=-1|Location.X=277|Location.Y=512|Color=8388608|FontID=1|IsHidden=T|Text=0.126 inch|Name=Length
|RECORD=41|OwnerIndex=1283|IndexInSheet=12|OwnerPartId=-1|Location.X=277|Location.Y=512|Color=8388608|FontID=1|IsHidden=T|Text=0.024 inch|Name=Height
|RECORD=41|OwnerIndex=1283|IndexInSheet=13|OwnerPartId=-1|Location.X=277|Location.Y=512|Color=8388608|FontID=1|IsHidden=T|Text=Surface Mount|Name=Mount
|RECORD=41|OwnerIndex=1283|IndexInSheet=14|OwnerPartId=-1|Location.X=277|Location.Y=512|Color=8388608|FontID=1|IsHidden=T|Text=1|Name=Package Quantity
|RECORD=41|OwnerIndex=1283|IndexInSheet=15|OwnerPartId=-1|Location.X=277|Location.Y=512|Color=8388608|FontID=1|IsHidden=T|Text=Apr-15|Name=DatasheetVersion
|RECORD=41|OwnerIndex=1283|IndexInSheet=16|OwnerPartId=-1|Location.X=277|Location.Y=512|Color=8388608|FontID=1|IsHidden=T|Text=Manufacturer URL|Name=ComponentLink1Description
|RECORD=41|OwnerIndex=1283|IndexInSheet=17|OwnerPartId=-1|Location.X=277|Location.Y=512|Color=8388608|FontID=1|IsHidden=T|Text=-55 degC|Name=Min Operating Temperature
|RECORD=41|OwnerIndex=1283|IndexInSheet=18|OwnerPartId=-1|Location.X=277|Location.Y=512|Color=8388608|FontID=1|IsHidden=T|Text=Tape and Reel|Name=Packaging
|RECORD=41|OwnerIndex=1283|IndexInSheet=19|OwnerPartId=-1|Location.X=277|Location.Y=512|Color=8388608|FontID=1|IsHidden=T|Text=No|Name=Radiation Hardening
|RECORD=41|OwnerIndex=1283|IndexInSheet=20|OwnerPartId=-1|Location.X=277|Location.Y=512|Color=8388608|FontID=6|IsHidden=T|Text=http://industrial.panasonic.com/cdbs/www-data/pdf/RDA0000/AOA0000C86.pdf|Name=ComponentLink2URL
|RECORD=41|OwnerIndex=1283|IndexInSheet=21|OwnerPartId=-1|Location.X=277|Location.Y=512|Color=8388608|FontID=1|IsHidden=T|Text=3216|Name=Case Code (Metric)
|RECORD=41|OwnerIndex=1283|IndexInSheet=22|OwnerPartId=-1|Location.X=277|Location.Y=512|Color=8388608|FontID=1|IsHidden=T|Text=8|Name=Pins
|RECORD=41|OwnerIndex=1283|IndexInSheet=23|OwnerPartId=-1|Location.X=277|Location.Y=512|Color=8388608|FontID=1|IsHidden=T|Text=1206|Name=Case Code (Imperial)
|RECORD=41|OwnerIndex=1283|IndexInSheet=24|OwnerPartId=-1|Location.X=277|Location.Y=512|Color=8388608|FontID=1|IsHidden=T|Text=Thick Film|Name=Type (Resistor)
|RECORD=41|OwnerIndex=1283|IndexInSheet=25|OwnerPartId=-1|Location.X=277|Location.Y=512|Color=8388608|FontID=1|IsHidden=T|Text=true|Name=RoHSCompliant
|RECORD=41|OwnerIndex=1283|IndexInSheet=26|OwnerPartId=-1|Location.X=277|Location.Y=512|Color=8388608|FontID=1|IsHidden=T|Text=5%|Name=Tolerance
|RECORD=41|OwnerIndex=1283|IndexInSheet=27|OwnerPartId=-1|Location.X=277|Location.Y=512|Color=8388608|FontID=1|IsHidden=T|Text=Datasheet|Name=ComponentLink2Description
|RECORD=41|OwnerIndex=1283|IndexInSheet=28|OwnerPartId=-1|Location.X=277|Location.Y=512|Color=8388608|FontID=1|IsHidden=T|Text=2-Pin Surface Mount Device, Body 1.6 x 0.85 mm|Name=PackageDescription
|RECORD=41|OwnerIndex=1283|IndexInSheet=29|OwnerPartId=-1|Location.X=277|Location.Y=512|Color=8388608|FontID=6|IsHidden=T|Text=http://www.panasonic.com/|Name=ComponentLink1URL
|RECORD=41|OwnerIndex=1283|IndexInSheet=30|OwnerPartId=-1|Location.X=277|Location.Y=512|Color=8388608|FontID=1|IsHidden=T|Text=250 mW|Name=Power Rating
|RECORD=34|OwnerIndex=1283|IndexInSheet=-1|OwnerPartId=-1|Location.X=283|Location.Y=491|Color=8388608|FontID=1|Text=R29|Name=Designator|ReadOnlyState=1
|RECORD=41|OwnerIndex=1283|IndexInSheet=-1|OwnerPartId=-1|Location.X=283|Location.Y=481|Color=8388608|FontID=1|Text=4.7K|Name=Comment
|RECORD=44|OwnerIndex=1283
|RECORD=45|OwnerIndex=1319|IndexInSheet=-1|Description=Chip Resistor, 2-Leads, Body 1.75x0.95mm, IPC Medium Density|UseComponentLibrary=T|ModelName=RESC1608X55X30NL15T15|ModelType=PCBLIB|DatafileCount=1|ModelDatafileEntity0=RESC1608X55X30NL15T15|ModelDatafileKind0=PCBLib|IsCurrent=T|DatalinksLocked=T|DatabaseDatalinksLocked=T
|RECORD=46|OwnerIndex=1320
|RECORD=48|OwnerIndex=1320
|RECORD=41|OwnerIndex=1322|IndexInSheet=-1|OwnerPartId=-1|Color=8388608|FontID=1|IsHidden=T|Text=2D|Name=Available Preview Images
|RECORD=45|OwnerIndex=1319|IndexInSheet=-1|Description=Chip Resistor, 2-Leads, Body 1.75x0.95mm, IPC Low Density|UseComponentLibrary=T|ModelName=RESC1608X55X30ML15T15|ModelType=PCBLIB|DatafileCount=1|ModelDatafileEntity0=RESC1608X55X30ML15T15|ModelDatafileKind0=PCBLib|DatalinksLocked=T|DatabaseDatalinksLocked=T
|RECORD=46|OwnerIndex=1324
|RECORD=48|OwnerIndex=1324
|RECORD=41|OwnerIndex=1326|IndexInSheet=-1|OwnerPartId=-1|Color=8388608|FontID=1|IsHidden=T|Text=2D|Name=Available Preview Images
|RECORD=45|OwnerIndex=1319|IndexInSheet=-1|Description=Chip Resistor, 2-Leads, Body 1.75x0.95mm, IPC High Density|UseComponentLibrary=T|ModelName=RESC1608X55X30LL15T15|ModelType=PCBLIB|DatafileCount=1|ModelDatafileEntity0=RESC1608X55X30LL15T15|ModelDatafileKind0=PCBLib|DatalinksLocked=T|DatabaseDatalinksLocked=T
|RECORD=46|OwnerIndex=1328
|RECORD=48|OwnerIndex=1328
|RECORD=41|OwnerIndex=1330|IndexInSheet=-1|OwnerPartId=-1|Color=8388608|FontID=1|IsHidden=T|Text=2D|Name=Available Preview Images
|RECORD=1|LibReference=RES-2|ComponentDescription=Precision Thick Film Chip Resistor, 4.7 KOhm, +/- 1%, -55 to 155 degC, 0603 (1608 Metric), RoHS, Tape and Reel ERJ-3EKF4701V|PartCount=2|DisplayModeCount=1|IndexInSheet=91|OwnerPartId=-1|Location.X=310|Location.Y=480|Orientation=1|CurrentPartId=1|LibraryPath=*|SourceLibraryName=Altium Content Vault|TargetFileName=*|AreaColor=11599871|Color=128|PartIDLocked=T|DesignItemId=CMP-1012-00586-3|AllPinCount=2
|RECORD=2|OwnerIndex=1332|OwnerPartId=1|FormalType=1|Electrical=4|PinConglomerate=33|PinLength=10|Location.X=310|Location.Y=500|Name=2|Designator=2|PinPropagationDelay=0.000000E+000
|RECORD=2|OwnerIndex=1332|OwnerPartId=1|FormalType=1|Electrical=4|PinConglomerate=35|PinLength=10|Location.X=310|Location.Y=480|Name=1|Designator=1|PinPropagationDelay=0.000000E+000
|RECORD=6|OwnerIndex=1332|IsNotAccesible=T|IndexInSheet=2|OwnerPartId=1|LineWidth=1|Color=16711680|LocationCount=10|X1=310|Y1=500|X2=310|Y2=496|X3=312|Y3=495|X4=308|Y4=493|X5=312|Y5=491|X6=308|Y6=489|X7=312|Y7=487|X8=308|Y8=485|X9=310|Y9=484|X10=310|Y10=480
|RECORD=41|OwnerIndex=1332|IndexInSheet=3|OwnerPartId=-1|Location.X=307|Location.Y=512|Color=8388608|FontID=1|IsHidden=T|Text=220 Ohm|Name=Resistance
|RECORD=41|OwnerIndex=1332|IndexInSheet=4|OwnerPartId=-1|Location.X=307|Location.Y=512|Color=8388608|FontID=1|IsHidden=T|Text=0603|Name=PackageReference
|RECORD=41|OwnerIndex=1332|IndexInSheet=5|OwnerPartId=-1|Location.X=307|Location.Y=512|Color=8388608|FontID=1|IsHidden=T|Text=50 V|Name=Voltage Rating
|RECORD=41|OwnerIndex=1332|IndexInSheet=6|OwnerPartId=-1|Location.X=307|Location.Y=512|Color=8388608|FontID=1|IsHidden=T|Text=125 degC|Name=Max Operating Temperature
|RECORD=41|OwnerIndex=1332|IndexInSheet=7|OwnerPartId=-1|Location.X=307|Location.Y=512|Color=8388608|FontID=1|IsHidden=T|Text=4|Name=Elements
|RECORD=41|OwnerIndex=1332|IndexInSheet=8|OwnerPartId=-1|Location.X=307|Location.Y=512|Color=8388608|FontID=1|IsHidden=T|Text=No SVHC|Name=REACH SVHC
|RECORD=41|OwnerIndex=1332|IndexInSheet=9|OwnerPartId=-1|Location.X=307|Location.Y=512|Color=8388608|FontID=1|IsHidden=T|Text=0.063 inch|Name=Width
|RECORD=41|OwnerIndex=1332|IndexInSheet=10|OwnerPartId=-1|Location.X=307|Location.Y=512|Color=8388608|FontID=1|IsHidden=T|Text=1205|Name=Case\Package
|RECORD=41|OwnerIndex=1332|IndexInSheet=11|OwnerPartId=-1|Location.X=307|Location.Y=512|Color=8388608|FontID=1|IsHidden=T|Text=0.126 inch|Name=Length
|RECORD=41|OwnerIndex=1332|IndexInSheet=12|OwnerPartId=-1|Location.X=307|Location.Y=512|Color=8388608|FontID=1|IsHidden=T|Text=0.024 inch|Name=Height
|RECORD=41|OwnerIndex=1332|IndexInSheet=13|OwnerPartId=-1|Location.X=307|Location.Y=512|Color=8388608|FontID=1|IsHidden=T|Text=Surface Mount|Name=Mount
|RECORD=41|OwnerIndex=1332|IndexInSheet=14|OwnerPartId=-1|Location.X=307|Location.Y=512|Color=8388608|FontID=1|IsHidden=T|Text=1|Name=Package Quantity
|RECORD=41|OwnerIndex=1332|IndexInSheet=15|OwnerPartId=-1|Location.X=307|Location.Y=512|Color=8388608|FontID=1|IsHidden=T|Text=Apr-15|Name=DatasheetVersion
|RECORD=41|OwnerIndex=1332|IndexInSheet=16|OwnerPartId=-1|Location.X=307|Location.Y=512|Color=8388608|FontID=1|IsHidden=T|Text=Manufacturer URL|Name=ComponentLink1Description
|RECORD=41|OwnerIndex=1332|IndexInSheet=17|OwnerPartId=-1|Location.X=307|Location.Y=512|Color=8388608|FontID=1|IsHidden=T|Text=-55 degC|Name=Min Operating Temperature
|RECORD=41|OwnerIndex=1332|IndexInSheet=18|OwnerPartId=-1|Location.X=307|Location.Y=512|Color=8388608|FontID=1|IsHidden=T|Text=Tape and Reel|Name=Packaging
|RECORD=41|OwnerIndex=1332|IndexInSheet=19|OwnerPartId=-1|Location.X=307|Location.Y=512|Color=8388608|FontID=1|IsHidden=T|Text=No|Name=Radiation Hardening
|RECORD=41|OwnerIndex=1332|IndexInSheet=20|OwnerPartId=-1|Location.X=307|Location.Y=512|Color=8388608|FontID=6|IsHidden=T|Text=http://industrial.panasonic.com/cdbs/www-data/pdf/RDA0000/AOA0000C86.pdf|Name=ComponentLink2URL
|RECORD=41|OwnerIndex=1332|IndexInSheet=21|OwnerPartId=-1|Location.X=307|Location.Y=512|Color=8388608|FontID=1|IsHidden=T|Text=3216|Name=Case Code (Metric)
|RECORD=41|OwnerIndex=1332|IndexInSheet=22|OwnerPartId=-1|Location.X=307|Location.Y=512|Color=8388608|FontID=1|IsHidden=T|Text=8|Name=Pins
|RECORD=41|OwnerIndex=1332|IndexInSheet=23|OwnerPartId=-1|Location.X=307|Location.Y=512|Color=8388608|FontID=1|IsHidden=T|Text=1206|Name=Case Code (Imperial)
|RECORD=41|OwnerIndex=1332|IndexInSheet=24|OwnerPartId=-1|Location.X=307|Location.Y=512|Color=8388608|FontID=1|IsHidden=T|Text=Thick Film|Name=Type (Resistor)
|RECORD=41|OwnerIndex=1332|IndexInSheet=25|OwnerPartId=-1|Location.X=307|Location.Y=512|Color=8388608|FontID=1|IsHidden=T|Text=true|Name=RoHSCompliant
|RECORD=41|OwnerIndex=1332|IndexInSheet=26|OwnerPartId=-1|Location.X=307|Location.Y=512|Color=8388608|FontID=1|IsHidden=T|Text=5%|Name=Tolerance
|RECORD=41|OwnerIndex=1332|IndexInSheet=27|OwnerPartId=-1|Location.X=307|Location.Y=512|Color=8388608|FontID=1|IsHidden=T|Text=Datasheet|Name=ComponentLink2Description
|RECORD=41|OwnerIndex=1332|IndexInSheet=28|OwnerPartId=-1|Location.X=307|Location.Y=512|Color=8388608|FontID=1|IsHidden=T|Text=2-Pin Surface Mount Device, Body 1.6 x 0.85 mm|Name=PackageDescription
|RECORD=41|OwnerIndex=1332|IndexInSheet=29|OwnerPartId=-1|Location.X=307|Location.Y=512|Color=8388608|FontID=6|IsHidden=T|Text=http://www.panasonic.com/|Name=ComponentLink1URL
|RECORD=41|OwnerIndex=1332|IndexInSheet=30|OwnerPartId=-1|Location.X=307|Location.Y=512|Color=8388608|FontID=1|IsHidden=T|Text=250 mW|Name=Power Rating
|RECORD=34|OwnerIndex=1332|IndexInSheet=-1|OwnerPartId=-1|Location.X=313|Location.Y=491|Color=8388608|FontID=1|Text=R30|Name=Designator|ReadOnlyState=1
|RECORD=41|OwnerIndex=1332|IndexInSheet=-1|OwnerPartId=-1|Location.X=313|Location.Y=481|Color=8388608|FontID=1|Text=4.7K|Name=Comment
|RECORD=44|OwnerIndex=1332
|RECORD=45|OwnerIndex=1368|IndexInSheet=-1|Description=Chip Resistor, 2-Leads, Body 1.75x0.95mm, IPC Medium Density|UseComponentLibrary=T|ModelName=RESC1608X55X30NL15T15|ModelType=PCBLIB|DatafileCount=1|ModelDatafileEntity0=RESC1608X55X30NL15T15|ModelDatafileKind0=PCBLib|IsCurrent=T|DatalinksLocked=T|DatabaseDatalinksLocked=T
|RECORD=46|OwnerIndex=1369
|RECORD=48|OwnerIndex=1369
|RECORD=41|OwnerIndex=1371|IndexInSheet=-1|OwnerPartId=-1|Color=8388608|FontID=1|IsHidden=T|Text=2D|Name=Available Preview Images
|RECORD=45|OwnerIndex=1368|IndexInSheet=-1|Description=Chip Resistor, 2-Leads, Body 1.75x0.95mm, IPC Low Density|UseComponentLibrary=T|ModelName=RESC1608X55X30ML15T15|ModelType=PCBLIB|DatafileCount=1|ModelDatafileEntity0=RESC1608X55X30ML15T15|ModelDatafileKind0=PCBLib|DatalinksLocked=T|DatabaseDatalinksLocked=T
|RECORD=46|OwnerIndex=1373
|RECORD=48|OwnerIndex=1373
|RECORD=41|OwnerIndex=1375|IndexInSheet=-1|OwnerPartId=-1|Color=8388608|FontID=1|IsHidden=T|Text=2D|Name=Available Preview Images
|RECORD=45|OwnerIndex=1368|IndexInSheet=-1|Description=Chip Resistor, 2-Leads, Body 1.75x0.95mm, IPC High Density|UseComponentLibrary=T|ModelName=RESC1608X55X30LL15T15|ModelType=PCBLIB|DatafileCount=1|ModelDatafileEntity0=RESC1608X55X30LL15T15|ModelDatafileKind0=PCBLib|DatalinksLocked=T|DatabaseDatalinksLocked=T
|RECORD=46|OwnerIndex=1377
|RECORD=48|OwnerIndex=1377
|RECORD=41|OwnerIndex=1379|IndexInSheet=-1|OwnerPartId=-1|Color=8388608|FontID=1|IsHidden=T|Text=2D|Name=Available Preview Images
|RECORD=17|IndexInSheet=92|OwnerPartId=-1|ShowNetName=T|Location.X=280|Location.Y=510|Orientation=1|Color=128|FontID=1|Text=+3.3V
|RECORD=17|IndexInSheet=93|OwnerPartId=-1|ShowNetName=T|Location.X=310|Location.Y=510|Orientation=1|Color=128|FontID=1|Text=+3.3V
|RECORD=17|IndexInSheet=94|OwnerPartId=-1|ShowNetName=T|Location.X=270|Location.Y=365|Orientation=2|Color=255|FontID=1|Text=ANT2_IN|IsCrossSheetConnector=T
|RECORD=1|LibReference=CAP|ComponentDescription=C0603X104K5RACAUTO|PartCount=2|DisplayModeCount=2|IndexInSheet=95|OwnerPartId=-1|Location.X=350|Location.Y=320|Orientation=3|CurrentPartId=1|SourceLibraryName=Altium Content Vault|TargetFileName=*|AreaColor=11599871|Color=128|PartIDLocked=F|DesignItemId=CMP-2006-00003-1|AllPinCount=2
|RECORD=2|OwnerIndex=1384|OwnerPartId=1|OwnerPartDisplayMode=1|FormalType=1|Electrical=4|PinConglomerate=33|PinLength=10|Location.X=340|Location.Y=320|Name=1|Designator=1|PinPropagationDelay=0.000000E+000
|RECORD=2|OwnerIndex=1384|OwnerPartId=1|OwnerPartDisplayMode=1|FormalType=1|Electrical=4|PinConglomerate=35|PinLength=10|Location.X=340|Location.Y=310|Name=2|Designator=2|PinPropagationDelay=0.000000E+000
|RECORD=13|OwnerIndex=1384|IsNotAccesible=T|IndexInSheet=2|OwnerPartId=1|OwnerPartDisplayMode=1|Location.X=332|Location.Y=320|Corner.X=348|Corner.Y=320|LineWidth=1|Color=16711680
|RECORD=13|OwnerIndex=1384|IsNotAccesible=T|IndexInSheet=3|OwnerPartId=1|OwnerPartDisplayMode=1|Location.X=340|Location.Y=316|Corner.X=340|Corner.Y=310|LineWidth=1|Color=16711680
|RECORD=12|OwnerIndex=1384|IsNotAccesible=T|IndexInSheet=4|OwnerPartId=1|OwnerPartDisplayMode=1|Location.X=340|Location.Y=300|Radius=16|LineWidth=1|StartAngle=61.000|EndAngle=90.000|Color=16711680
|RECORD=12|OwnerIndex=1384|IsNotAccesible=T|IndexInSheet=5|OwnerPartId=1|OwnerPartDisplayMode=1|Location.X=340|Location.Y=300|Radius=16|LineWidth=1|StartAngle=90.000|EndAngle=119.000|Color=16711680
|RECORD=2|OwnerIndex=1384|OwnerPartId=1|FormalType=1|Electrical=4|PinConglomerate=33|PinLength=10|Location.X=340|Location.Y=320|Name=1|Designator=1|PinPropagationDelay=0.000000E+000
|RECORD=2|OwnerIndex=1384|OwnerPartId=1|FormalType=1|Electrical=4|PinConglomerate=35|PinLength=10|Location.X=340|Location.Y=310|Name=2|Designator=2|PinPropagationDelay=0.000000E+000
|RECORD=13|OwnerIndex=1384|IsNotAccesible=T|IndexInSheet=8|OwnerPartId=1|Location.X=348|Location.Y=313|Corner.X=332|Corner.Y=313|LineWidth=1|Color=16711680
|RECORD=13|OwnerIndex=1384|IsNotAccesible=T|IndexInSheet=9|OwnerPartId=1|Location.X=332|Location.Y=317|Corner.X=348|Corner.Y=317|LineWidth=1|Color=16711680
|RECORD=6|OwnerIndex=1384|IsNotAccesible=T|IndexInSheet=10|OwnerPartId=1|LineWidth=1|Color=16711680|LocationCount=2|X1=340|Y1=320|X2=340|Y2=317
|RECORD=6|OwnerIndex=1384|IsNotAccesible=T|IndexInSheet=11|OwnerPartId=1|LineWidth=1|Color=16711680|LocationCount=2|X1=340|Y1=310|X2=340|Y2=313
|RECORD=41|OwnerIndex=1384|IndexInSheet=12|OwnerPartId=-1|Location.X=331|Location.Y=332|Color=8388608|FontID=1|IsHidden=T|Text=Kemet|Name=Manufacturer
|RECORD=41|OwnerIndex=1384|IndexInSheet=13|OwnerPartId=-1|Location.X=331|Location.Y=332|Color=8388608|FontID=1|IsHidden=T|Text=C0603X104K5RACAUTO|Name=Part Number
|RECORD=34|OwnerIndex=1384|IndexInSheet=-1|OwnerPartId=-1|Location.X=349|Location.Y=307|Color=8388608|FontID=1|Text=C28|Name=Designator|ReadOnlyState=1
|RECORD=41|OwnerIndex=1384|IndexInSheet=-1|OwnerPartId=-1|Location.X=349|Location.Y=293|Color=8388608|FontID=1|Text=0.1uF|Name=Comment
|RECORD=44|OwnerIndex=1384
|RECORD=45|OwnerIndex=1405|IndexInSheet=-1|Description=Chip Capacitor, 2-Leads, Body 1.60x0.80mm, IPC Low Density|UseComponentLibrary=T|ModelName=CAPC1608X87X45ML20T05|ModelType=PCBLIB|DatafileCount=1|ModelDatafileEntity0=CAPC1608X87X45ML20T05|ModelDatafileKind0=PCBLib|IsCurrent=T|DatalinksLocked=T|DatabaseDatalinksLocked=T
|RECORD=46|OwnerIndex=1406
|RECORD=48|OwnerIndex=1406
|RECORD=41|OwnerIndex=1408|IndexInSheet=-1|OwnerPartId=-1|Color=8388608|FontID=1|Text=2D|Name=Available Preview Images
|RECORD=45|OwnerIndex=1405|IndexInSheet=-1|Description=Chip Capacitor, 2-Leads, Body 1.60x0.80mm, IPC High Density|UseComponentLibrary=T|ModelName=CAPC1608X87X45LL20T05|ModelType=PCBLIB|DatafileCount=1|ModelDatafileEntity0=CAPC1608X87X45LL20T05|ModelDatafileKind0=PCBLib|DatalinksLocked=T|DatabaseDatalinksLocked=T
|RECORD=46|OwnerIndex=1410
|RECORD=48|OwnerIndex=1410
|RECORD=41|OwnerIndex=1412|IndexInSheet=-1|OwnerPartId=-1|Color=8388608|FontID=1|Text=2D|Name=Available Preview Images
|RECORD=45|OwnerIndex=1405|IndexInSheet=-1|Description=Chip Capacitor, 2-Leads, Body 1.60x0.80mm, IPC Medium Density|UseComponentLibrary=T|ModelName=CAPC1608X87X45NL20T05|ModelType=PCBLIB|DatafileCount=1|ModelDatafileEntity0=CAPC1608X87X45NL20T05|ModelDatafileKind0=PCBLib|DatalinksLocked=T|DatabaseDatalinksLocked=T
|RECORD=46|OwnerIndex=1414
|RECORD=48|OwnerIndex=1414
|RECORD=41|OwnerIndex=1416|IndexInSheet=-1|OwnerPartId=-1|Color=8388608|FontID=1|Text=2D|Name=Available Preview Images
|RECORD=17|IndexInSheet=96|OwnerPartId=-1|Style=4|ShowNetName=T|Location.X=390|Location.Y=290|Orientation=3|Color=128|FontID=1|Text=GND
|RECORD=17|IndexInSheet=97|OwnerPartId=-1|Style=4|ShowNetName=T|Location.X=340|Location.Y=290|Orientation=3|Color=128|FontID=1|Text=GND
|RECORD=17|IndexInSheet=98|OwnerPartId=-1|ShowNetName=T|Location.X=340|Location.Y=510|Orientation=1|Color=128|FontID=1|Text=+3.3V
|RECORD=1|LibReference=WE-TVS-HS-4|ComponentDescription=TVS Diode WE-TVS-HS, VRWM=3.3V|PartCount=2|DisplayModeCount=1|IndexInSheet=99|OwnerPartId=-1|Location.X=1340|Location.Y=560|Orientation=1|CurrentPartId=1|LibraryPath=*|SourceLibraryName=Altium Content Vault|TargetFileName=*|AreaColor=11599871|Color=128|PartIDLocked=F|DesignItemId=CMP-1486-00002-1|AllPinCount=4
|RECORD=14|OwnerIndex=1421|IsNotAccesible=T|OwnerPartId=1|Location.X=1334|Location.Y=537|Corner.X=1374|Corner.Y=575|AreaColor=11599871|IsSolid=T|Transparent=T
|RECORD=6|OwnerIndex=1421|IsNotAccesible=T|IndexInSheet=1|OwnerPartId=1|LineWidth=1|Color=16711680|LocationCount=4|X1=1344|X1_Frac=10000|Y1=561|Y1_Frac=40000|X2=1342|X2_Frac=10000|Y2=559|Y2_Frac=40000|X3=1338|X3_Frac=10000|Y3=559|Y3_Frac=40000|X4=1336|X4_Frac=10000|Y4=557|Y4_Frac=40000
|RECORD=7|OwnerIndex=1421|IsNotAccesible=T|IndexInSheet=2|OwnerPartId=1|LineWidth=1|Color=16711680|AreaColor=16711680|IsSolid=T|LocationCount=3|X1=1344|X1_Frac=90000|Y1=553|Y1_Frac=50000|X2=1339|X2_Frac=90000|Y2=558|Y2_Frac=50000|X3=1334|X3_Frac=90000|Y3=553|Y3_Frac=50000
|RECORD=12|OwnerIndex=1421|IsNotAccesible=T|IndexInSheet=3|OwnerPartId=1|Location.X=1351|Location.Y=558|Radius_Frac=63392|LineWidth=1|StartAngle=57.394|EndAngle=30.947
|RECORD=6|OwnerIndex=1421|IsNotAccesible=T|IndexInSheet=4|OwnerPartId=1|LineWidth=1|LocationCount=2|X1=1360|Y1=558|X2=1351|Y2=558
|RECORD=7|OwnerIndex=1421|IsNotAccesible=T|IndexInSheet=5|OwnerPartId=1|LineWidth=1|Color=16711680|AreaColor=16711680|LocationCount=3|X1=1355|X1_Frac=90000|Y1=545|Y1_Frac=50000|X2=1350|X2_Frac=90000|Y2=550|Y2_Frac=50000|X3=1345|X3_Frac=90000|Y3=545|Y3_Frac=50000
|RECORD=6|OwnerIndex=1421|IsNotAccesible=T|IndexInSheet=6|OwnerPartId=1|LineWidth=1|Color=16711680|LocationCount=2|X1=1347|Y1=551|X2=1354|X2_Frac=87402|Y2=551
|RECORD=7|OwnerIndex=1421|IsNotAccesible=T|IndexInSheet=7|OwnerPartId=1|LineWidth=1|Color=16711680|AreaColor=16711680|LocationCount=3|X1=1355|X1_Frac=90000|Y1=561|Y1_Frac=50000|X2=1350|X2_Frac=90000|Y2=566|Y2_Frac=50000|X3=1345|X3_Frac=90000|Y3=561|Y3_Frac=50000
|RECORD=6|OwnerIndex=1421|IsNotAccesible=T|IndexInSheet=8|OwnerPartId=1|LineWidth=1|Color=16711680|LocationCount=2|X1=1347|Y1=567|X2=1354|X2_Frac=87402|Y2=567
|RECORD=6|OwnerIndex=1421|IsNotAccesible=T|IndexInSheet=9|OwnerPartId=1|LineWidth=1|LocationCount=2|X1=1351|Y1=551|X2=1351|Y2=561
|RECORD=6|OwnerIndex=1421|IsNotAccesible=T|IndexInSheet=10|OwnerPartId=1|LineWidth=1|LocationCount=2|X1=1351|Y1=567|X2=1351|Y2=573
|RECORD=6|OwnerIndex=1421|IsNotAccesible=T|IndexInSheet=11|OwnerPartId=1|LineWidth=1|LocationCount=2|X1=1340|Y1=560|X2=1340|Y2=573
|RECORD=6|OwnerIndex=1421|IsNotAccesible=T|IndexInSheet=12|OwnerPartId=1|LineWidth=1|LocationCount=2|X1=1340|Y1=539|X2=1340|Y2=553
|RECORD=6|OwnerIndex=1421|IsNotAccesible=T|IndexInSheet=13|OwnerPartId=1|LineWidth=1|LocationCount=2|X1=1351|Y1=539|X2=1351|Y2=545
|RECORD=6|OwnerIndex=1421|IsNotAccesible=T|IndexInSheet=14|OwnerPartId=1|LineWidth=1|LocationCount=2|X1=1340|Y1=539|X2=1368|Y2=539
|RECORD=6|OwnerIndex=1421|IsNotAccesible=T|IndexInSheet=15|OwnerPartId=1|LineWidth=1|LocationCount=2|X1=1340|Y1=573|X2=1368|Y2=573
|RECORD=6|OwnerIndex=1421|IsNotAccesible=T|IndexInSheet=16|OwnerPartId=1|LineWidth=1|LocationCount=2|X1=1360|Y1=554|X2=1360|Y2=540
|RECORD=2|OwnerIndex=1421|OwnerPartId=1|FormalType=1|Electrical=4|PinConglomerate=51|PinLength=10|Location.X=1340|Location.Y=540|Name=GND|Designator=1|PinPropagationDelay=0.000000E+000
|RECORD=2|OwnerIndex=1421|OwnerPartId=1|FormalType=1|Electrical=4|PinConglomerate=51|PinLength=10|Location.X=1360|Location.Y=540|Name=I/O1|Designator=2|PinPropagationDelay=0.000000E+000
|RECORD=2|OwnerIndex=1421|OwnerPartId=1|FormalType=1|Electrical=4|PinConglomerate=49|PinLength=10|Location.X=1360|Location.Y=570|Name=I/O2|Designator=3|PinPropagationDelay=0.000000E+000
|RECORD=2|OwnerIndex=1421|OwnerPartId=1|FormalType=1|Electrical=4|PinConglomerate=49|PinLength=10|Location.X=1340|Location.Y=570|Name=VDD|Designator=4|PinPropagationDelay=0.000000E+000
|RECORD=12|OwnerIndex=1421|IsNotAccesible=T|IndexInSheet=21|OwnerPartId=1|Location.X=1340|Location.Y=573|Radius_Frac=63392|LineWidth=1|StartAngle=57.394|EndAngle=30.947
|RECORD=12|OwnerIndex=1421|IsNotAccesible=T|IndexInSheet=22|OwnerPartId=1|Location.X=1340|Location.Y=539|Radius_Frac=63392|LineWidth=1|StartAngle=57.394|EndAngle=30.947
|RECORD=12|OwnerIndex=1421|IsNotAccesible=T|IndexInSheet=23|OwnerPartId=1|Location.X=1368|Location.Y=554|Radius_Frac=63392|LineWidth=1|StartAngle=57.394|EndAngle=30.947
|RECORD=6|OwnerIndex=1421|IsNotAccesible=T|IndexInSheet=24|OwnerPartId=1|LineWidth=1|LocationCount=2|X1=1360|Y1=554|X2=1368|Y2=554
|RECORD=7|OwnerIndex=1421|IsNotAccesible=T|IndexInSheet=25|OwnerPartId=1|LineWidth=1|Color=16711680|AreaColor=16711680|LocationCount=3|X1=1372|X1_Frac=90000|Y1=545|Y1_Frac=50000|X2=1367|X2_Frac=90000|Y2=550|Y2_Frac=50000|X3=1362|X3_Frac=90000|Y3=545|Y3_Frac=50000
|RECORD=6|OwnerIndex=1421|IsNotAccesible=T|IndexInSheet=26|OwnerPartId=1|LineWidth=1|Color=16711680|LocationCount=2|X1=1364|Y1=551|X2=1371|X2_Frac=87402|Y2=551
|RECORD=7|OwnerIndex=1421|IsNotAccesible=T|IndexInSheet=27|OwnerPartId=1|LineWidth=1|Color=16711680|AreaColor=16711680|LocationCount=3|X1=1372|X1_Frac=90000|Y1=561|Y1_Frac=50000|X2=1367|X2_Frac=90000|Y2=566|Y2_Frac=50000|X3=1362|X3_Frac=90000|Y3=561|Y3_Frac=50000
|RECORD=6|OwnerIndex=1421|IsNotAccesible=T|IndexInSheet=28|OwnerPartId=1|LineWidth=1|Color=16711680|LocationCount=2|X1=1364|Y1=567|X2=1371|X2_Frac=87402|Y2=567
|RECORD=6|OwnerIndex=1421|IsNotAccesible=T|IndexInSheet=29|OwnerPartId=1|LineWidth=1|LocationCount=2|X1=1368|Y1=551|X2=1368|Y2=561
|RECORD=6|OwnerIndex=1421|IsNotAccesible=T|IndexInSheet=30|OwnerPartId=1|LineWidth=1|LocationCount=2|X1=1368|Y1=567|X2=1368|Y2=573
|RECORD=6|OwnerIndex=1421|IsNotAccesible=T|IndexInSheet=31|OwnerPartId=1|LineWidth=1|LocationCount=2|X1=1368|Y1=539|X2=1368|Y2=545
|RECORD=12|OwnerIndex=1421|IsNotAccesible=T|IndexInSheet=32|OwnerPartId=1|Location.X=1351|Location.Y=573|Radius_Frac=63392|LineWidth=1|StartAngle=57.394|EndAngle=30.947
|RECORD=12|OwnerIndex=1421|IsNotAccesible=T|IndexInSheet=33|OwnerPartId=1|Location.X=1351|Location.Y=539|Radius_Frac=63392|LineWidth=1|StartAngle=57.394|EndAngle=30.947
|RECORD=6|OwnerIndex=1421|IsNotAccesible=T|IndexInSheet=34|OwnerPartId=1|LineWidth=1|LocationCount=2|X1=1360|Y1=558|X2=1360|Y2=575
|RECORD=41|OwnerIndex=1421|IndexInSheet=35|OwnerPartId=-1|Location.X=1333|Location.X_Frac=90000|Location.Y=582|Color=8388608|FontID=1|IsHidden=T|Text=8240136|Name=PartNumber
|RECORD=41|OwnerIndex=1421|IndexInSheet=36|OwnerPartId=-1|Location.X=1333|Location.X_Frac=90000|Location.Y=582|Color=8388608|FontID=1|IsHidden=T|Text=Manufacturer URL|Name=ComponentLink1Description
|RECORD=41|OwnerIndex=1421|IndexInSheet=37|OwnerPartId=-1|Location.X=1333|Location.X_Frac=90000|Location.Y=582|Color=8388608|FontID=1|IsHidden=T|Text=Wuerth Elektronik|Name=Manufacturer
|RECORD=41|OwnerIndex=1421|IndexInSheet=38|OwnerPartId=-1|Location.X=1333|Location.X_Frac=90000|Location.Y=582|Color=8388608|FontID=1|IsHidden=T|Text=SOT143-4L|Name=PackageReference
|RECORD=41|OwnerIndex=1421|IndexInSheet=39|OwnerPartId=-1|Location.X=1333|Location.X_Frac=90000|Location.Y=582|Color=8388608|FontID=6|IsHidden=T|Text=http://www.we-online.com|Name=ComponentLink1URL
|RECORD=41|OwnerIndex=1421|IndexInSheet=40|OwnerPartId=-1|Location.X=1333|Location.X_Frac=90000|Location.Y=582|Color=8388608|FontID=1|IsHidden=T|Text=3.3V|Name=Reverse Stand Off Voltage
|RECORD=41|OwnerIndex=1421|IndexInSheet=41|OwnerPartId=-1|Location.X=1333|Location.X_Frac=90000|Location.Y=582|Color=8388608|FontID=1|IsHidden=T|Text=Datasheet|Name=ComponentLink2Description
|RECORD=41|OwnerIndex=1421|IndexInSheet=42|OwnerPartId=-1|Location.X=1333|Location.X_Frac=90000|Location.Y=582|Color=8388608|FontID=6|IsHidden=T|Text=http://katalog.we-online.de/kataloge/eisos/media/pdf/8240136.pdf|Name=ComponentLink2URL
|RECORD=34|OwnerIndex=1421|IndexInSheet=-1|OwnerPartId=-1|Location.X=1374|Location.Y=566|Color=8388608|FontID=1|Text=D2|Name=Designator|ReadOnlyState=1
|RECORD=41|OwnerIndex=1421|IndexInSheet=-1|OwnerPartId=-1|Location.X=1374|Location.Y=556|Color=8388608|FontID=1|Text=8240136|Name=Comment
|RECORD=44|OwnerIndex=1421
|RECORD=45|OwnerIndex=1471|IndexInSheet=-1|Description=SOT143-4L, 4-Leads, Body 2.95x2.4mm, Pitch 1.70/1.90mm|UseComponentLibrary=T|ModelName=SOT143-4L|ModelType=PCBLIB|DatafileCount=1|ModelDatafileEntity0=SOT143-4L|ModelDatafileKind0=PCBLib|IsCurrent=T|DatalinksLocked=T|DatabaseDatalinksLocked=T
|RECORD=46|OwnerIndex=1472
|RECORD=48|OwnerIndex=1472
|RECORD=41|OwnerIndex=1474|IndexInSheet=-1|OwnerPartId=-1|Color=8388608|FontID=1|IsHidden=T|Text=2D|Name=Available Preview Images
|RECORD=17|IndexInSheet=100|OwnerPartId=-1|ShowNetName=T|Location.X=580|Location.Y=600|Orientation=1|Color=128|FontID=1|Text=+3.3V
|RECORD=17|IndexInSheet=101|OwnerPartId=-1|Style=4|ShowNetName=T|Location.X=580|Location.Y=510|Orientation=3|Color=128|FontID=1|Text=GND
|RECORD=17|IndexInSheet=102|OwnerPartId=-1|ShowNetName=T|Location.X=1340|Location.Y=600|Orientation=1|Color=128|FontID=1|Text=+3.3V
|RECORD=17|IndexInSheet=103|OwnerPartId=-1|Style=4|ShowNetName=T|Location.X=1340|Location.Y=510|Orientation=3|Color=128|FontID=1|Text=GND
|RECORD=4|IndexInSheet=104|OwnerPartId=-1|Location.X=750|Location.Y=900|Color=8388608|FontID=5|Text=INPUT/OUTPUT SIGNALS
|RECORD=17|IndexInSheet=105|OwnerPartId=-1|ShowNetName=T|Location.X=210|Location.Y=775|Orientation=2|Color=255|FontID=1|Text=ANT1_IO_OUT|IsCrossSheetConnector=T
|RECORD=17|IndexInSheet=106|OwnerPartId=-1|ShowNetName=T|Location.X=210|Location.Y=720|Orientation=2|Color=255|FontID=1|Text=ANT1_IO_IN|IsCrossSheetConnector=T
|RECORD=17|IndexInSheet=107|OwnerPartId=-1|ShowNetName=T|Location.X=210|Location.Y=445|Orientation=2|Color=255|FontID=1|Text=ANT2_IO_OUT|IsCrossSheetConnector=T
|RECORD=17|IndexInSheet=108|OwnerPartId=-1|ShowNetName=T|Location.X=210|Location.Y=390|Orientation=2|Color=255|FontID=1|Text=ANT2_IO_IN|IsCrossSheetConnector=T
|RECORD=17|IndexInSheet=109|OwnerPartId=-1|ShowNetName=T|Location.X=970|Location.Y=775|Orientation=2|Color=255|FontID=1|Text=ANT3_IO_OUT|IsCrossSheetConnector=T
|RECORD=17|IndexInSheet=110|OwnerPartId=-1|ShowNetName=T|Location.X=970|Location.Y=720|Orientation=2|Color=255|FontID=1|Text=ANT3_IO_IN|IsCrossSheetConnector=T
|RECORD=17|IndexInSheet=111|OwnerPartId=-1|ShowNetName=T|Location.X=970|Location.Y=445|Orientation=2|Color=255|FontID=1|Text=ANT4_IO_OUT|IsCrossSheetConnector=T
|RECORD=17|IndexInSheet=112|OwnerPartId=-1|ShowNetName=T|Location.X=970|Location.Y=390|Orientation=2|Color=255|FontID=1|Text=ANT4_IO_IN|IsCrossSheetConnector=T
|RECORD=27|IndexInSheet=113|OwnerPartId=-1|LineWidth=1|Color=8388608|LocationCount=2|X1=670|Y1=640|X2=670|Y2=625
|RECORD=27|IndexInSheet=114|OwnerPartId=-1|LineWidth=1|Color=8388608|LocationCount=2|X1=660|Y1=640|X2=660|Y2=625
|RECORD=27|IndexInSheet=115|OwnerPartId=-1|LineWidth=1|Color=8388608|LocationCount=3|X1=680|Y1=625|X2=710|Y2=625|X3=710|Y3=620
|RECORD=27|IndexInSheet=116|OwnerPartId=-1|LineWidth=1|Color=8388608|LocationCount=2|X1=630|Y1=670|X2=600|Y2=670
|RECORD=27|IndexInSheet=117|OwnerPartId=-1|LineWidth=1|Color=8388608|LocationCount=2|X1=280|Y1=800|X2=280|Y2=775
|RECORD=27|IndexInSheet=118|OwnerPartId=-1|LineWidth=1|Color=8388608|LocationCount=2|X1=310|Y1=800|X2=310|Y2=720
|RECORD=27|IndexInSheet=119|OwnerPartId=-1|LineWidth=1|Color=8388608|LocationCount=4|X1=650|Y1=720|X2=670|Y2=720|X3=710|Y3=720|X4=710|Y4=710
|RECORD=27|IndexInSheet=120|OwnerPartId=-1|LineWidth=1|Color=8388608|LocationCount=2|X1=600|Y1=750|X2=600|Y2=670
|RECORD=27|IndexInSheet=121|OwnerPartId=-1|LineWidth=1|Color=8388608|LocationCount=3|X1=510|Y1=695|X2=520|Y2=695|X3=520|Y3=750
|RECORD=27|IndexInSheet=122|OwnerPartId=-1|LineWidth=1|Color=8388608|LocationCount=3|X1=400|Y1=675|X2=340|Y2=675|X3=340|Y3=660
|RECORD=27|IndexInSheet=123|OwnerPartId=-1|LineWidth=1|Color=8388608|LocationCount=3|X1=400|Y1=665|X2=390|Y2=665|X3=390|Y3=620
|RECORD=27|IndexInSheet=124|OwnerPartId=-1|LineWidth=1|Color=8388608|LocationCount=2|X1=340|Y1=620|X2=340|Y2=630
|RECORD=27|IndexInSheet=125|OwnerPartId=-1|LineWidth=1|Color=8388608|LocationCount=2|X1=340|Y1=675|X2=340|Y2=840
|RECORD=27|IndexInSheet=126|OwnerPartId=-1|LineWidth=1|Color=8388608|LocationCount=2|X1=1430|Y1=640|X2=1430|Y2=625
|RECORD=27|IndexInSheet=127|OwnerPartId=-1|LineWidth=1|Color=8388608|LocationCount=2|X1=1420|Y1=640|X2=1420|Y2=625
|RECORD=27|IndexInSheet=128|OwnerPartId=-1|LineWidth=1|Color=8388608|LocationCount=3|X1=1440|Y1=625|X2=1470|Y2=625|X3=1470|Y3=620
|RECORD=27|IndexInSheet=129|OwnerPartId=-1|LineWidth=1|Color=8388608|LocationCount=2|X1=1390|Y1=670|X2=1360|Y2=670
|RECORD=27|IndexInSheet=130|OwnerPartId=-1|LineWidth=1|Color=8388608|LocationCount=2|X1=1040|Y1=800|X2=1040|Y2=775
|RECORD=27|IndexInSheet=131|OwnerPartId=-1|LineWidth=1|Color=8388608|LocationCount=2|X1=1070|Y1=800|X2=1070|Y2=720
|RECORD=27|IndexInSheet=132|OwnerPartId=-1|LineWidth=1|Color=8388608|LocationCount=4|X1=1410|Y1=720|X2=1430|Y2=720|X3=1470|Y3=720|X4=1470|Y4=710
|RECORD=27|IndexInSheet=133|OwnerPartId=-1|LineWidth=1|Color=8388608|LocationCount=2|X1=1360|Y1=750|X2=1360|Y2=670
|RECORD=27|IndexInSheet=134|OwnerPartId=-1|LineWidth=1|Color=8388608|LocationCount=3|X1=1270|Y1=695|X2=1280|Y2=695|X3=1280|Y3=750
|RECORD=27|IndexInSheet=135|OwnerPartId=-1|LineWidth=1|Color=8388608|LocationCount=3|X1=1160|Y1=675|X2=1100|Y2=675|X3=1100|Y3=660
|RECORD=27|IndexInSheet=136|OwnerPartId=-1|LineWidth=1|Color=8388608|LocationCount=3|X1=1160|Y1=665|X2=1150|Y2=665|X3=1150|Y3=620
|RECORD=27|IndexInSheet=137|OwnerPartId=-1|LineWidth=1|Color=8388608|LocationCount=2|X1=1100|Y1=620|X2=1100|Y2=630
|RECORD=27|IndexInSheet=138|OwnerPartId=-1|LineWidth=1|Color=8388608|LocationCount=2|X1=1100|Y1=675|X2=1100|Y2=840
|RECORD=27|IndexInSheet=139|OwnerPartId=-1|LineWidth=1|Color=8388608|LocationCount=2|X1=1430|Y1=310|X2=1430|Y2=295
|RECORD=27|IndexInSheet=140|OwnerPartId=-1|LineWidth=1|Color=8388608|LocationCount=2|X1=1420|Y1=310|X2=1420|Y2=295
|RECORD=27|IndexInSheet=141|OwnerPartId=-1|LineWidth=1|Color=8388608|LocationCount=3|X1=1440|Y1=295|X2=1470|Y2=295|X3=1470|Y3=290
|RECORD=27|IndexInSheet=142|OwnerPartId=-1|LineWidth=1|Color=8388608|LocationCount=2|X1=1040|Y1=470|X2=1040|Y2=445
|RECORD=27|IndexInSheet=143|OwnerPartId=-1|LineWidth=1|Color=8388608|LocationCount=2|X1=1070|Y1=470|X2=1070|Y2=390
|RECORD=27|IndexInSheet=144|OwnerPartId=-1|LineWidth=1|Color=8388608|LocationCount=4|X1=1410|Y1=390|X2=1430|Y2=390|X3=1470|Y3=390|X4=1470|Y4=380
|RECORD=27|IndexInSheet=145|OwnerPartId=-1|LineWidth=1|Color=8388608|LocationCount=3|X1=1270|Y1=365|X2=1280|Y2=365|X3=1280|Y3=420
|RECORD=27|IndexInSheet=146|OwnerPartId=-1|LineWidth=1|Color=8388608|LocationCount=3|X1=1160|Y1=345|X2=1100|Y2=345|X3=1100|Y3=330
|RECORD=27|IndexInSheet=147|OwnerPartId=-1|LineWidth=1|Color=8388608|LocationCount=3|X1=1160|Y1=335|X2=1150|Y2=335|X3=1150|Y3=290
|RECORD=27|IndexInSheet=148|OwnerPartId=-1|LineWidth=1|Color=8388608|LocationCount=2|X1=1100|Y1=290|X2=1100|Y2=300
|RECORD=27|IndexInSheet=149|OwnerPartId=-1|LineWidth=1|Color=8388608|LocationCount=2|X1=1100|Y1=345|X2=1100|Y2=510
|RECORD=27|IndexInSheet=150|OwnerPartId=-1|LineWidth=1|Color=8388608|LocationCount=2|X1=670|Y1=310|X2=670|Y2=295
|RECORD=27|IndexInSheet=151|OwnerPartId=-1|LineWidth=1|Color=8388608|LocationCount=2|X1=660|Y1=310|X2=660|Y2=295
|RECORD=27|IndexInSheet=152|OwnerPartId=-1|LineWidth=1|Color=8388608|LocationCount=3|X1=680|Y1=295|X2=710|Y2=295|X3=710|Y3=290
|RECORD=27|IndexInSheet=153|OwnerPartId=-1|LineWidth=1|Color=8388608|LocationCount=2|X1=280|Y1=470|X2=280|Y2=445
|RECORD=27|IndexInSheet=154|OwnerPartId=-1|LineWidth=1|Color=8388608|LocationCount=2|X1=310|Y1=470|X2=310|Y2=390
|RECORD=27|IndexInSheet=155|OwnerPartId=-1|LineWidth=1|Color=8388608|LocationCount=4|X1=650|Y1=390|X2=670|Y2=390|X3=710|Y3=390|X4=710|Y4=380
|RECORD=27|IndexInSheet=156|OwnerPartId=-1|LineWidth=1|Color=8388608|LocationCount=3|X1=510|Y1=365|X2=520|Y2=365|X3=520|Y3=420
|RECORD=27|IndexInSheet=157|OwnerPartId=-1|LineWidth=1|Color=8388608|LocationCount=3|X1=400|Y1=345|X2=340|Y2=345|X3=340|Y3=330
|RECORD=27|IndexInSheet=158|OwnerPartId=-1|LineWidth=1|Color=8388608|LocationCount=3|X1=400|Y1=335|X2=390|Y2=335|X3=390|Y3=290
|RECORD=27|IndexInSheet=159|OwnerPartId=-1|LineWidth=1|Color=8388608|LocationCount=2|X1=340|Y1=290|X2=340|Y2=300
|RECORD=27|IndexInSheet=160|OwnerPartId=-1|LineWidth=1|Color=8388608|LocationCount=2|X1=340|Y1=345|X2=340|Y2=510
|RECORD=27|IndexInSheet=161|OwnerPartId=-1|LineWidth=1|Color=8388608|LocationCount=2|X1=600|Y1=580|X2=600|Y2=670
|RECORD=27|IndexInSheet=162|OwnerPartId=-1|LineWidth=1|Color=8388608|LocationCount=2|X1=600|Y1=530|X2=600|Y2=420
|RECORD=27|IndexInSheet=163|OwnerPartId=-1|LineWidth=1|Color=8388608|LocationCount=2|X1=1360|Y1=580|X2=1360|Y2=670
|RECORD=27|IndexInSheet=164|OwnerPartId=-1|LineWidth=1|Color=8388608|LocationCount=2|X1=1360|Y1=530|X2=1360|Y2=420
|RECORD=27|IndexInSheet=165|OwnerPartId=-1|LineWidth=1|Color=8388608|LocationCount=2|X1=580|Y1=580|X2=580|Y2=600
|RECORD=27|IndexInSheet=166|OwnerPartId=-1|LineWidth=1|Color=8388608|LocationCount=2|X1=580|Y1=510|X2=580|Y2=530
|RECORD=27|IndexInSheet=167|OwnerPartId=-1|LineWidth=1|Color=8388608|LocationCount=2|X1=1340|Y1=580|X2=1340|Y2=600
|RECORD=27|IndexInSheet=168|OwnerPartId=-1|LineWidth=1|Color=8388608|LocationCount=2|X1=1340|Y1=510|X2=1340|Y2=530
|RECORD=27|IndexInSheet=169|OwnerPartId=-1|LineWidth=1|Color=8388608|LocationCount=3|X1=510|Y1=420|X2=520|Y2=420|X3=535|Y3=420
|RECORD=27|IndexInSheet=170|OwnerPartId=-1|LineWidth=1|Color=8388608|LocationCount=3|X1=510|Y1=750|X2=520|Y2=750|X3=535|Y3=750
|RECORD=27|IndexInSheet=171|OwnerPartId=-1|LineWidth=1|Color=8388608|LocationCount=6|X1=680|Y1=310|X2=680|Y2=295|X3=670|Y3=295|X4=660|Y4=295|X5=650|Y5=295|X6=650|Y6=310
|RECORD=27|IndexInSheet=172|OwnerPartId=-1|LineWidth=1|Color=8388608|LocationCount=6|X1=680|Y1=640|X2=680|Y2=625|X3=670|Y3=625|X4=660|Y4=625|X5=650|Y5=625|X6=650|Y6=640
|RECORD=27|IndexInSheet=173|OwnerPartId=-1|LineWidth=1|Color=8388608|LocationCount=3|X1=1270|Y1=420|X2=1280|Y2=420|X3=1295|Y3=420
|RECORD=27|IndexInSheet=174|OwnerPartId=-1|LineWidth=1|Color=8388608|LocationCount=3|X1=1270|Y1=750|X2=1280|Y2=750|X3=1295|Y3=750
|RECORD=27|IndexInSheet=175|OwnerPartId=-1|LineWidth=1|Color=8388608|LocationCount=6|X1=1440|Y1=310|X2=1440|Y2=295|X3=1430|Y3=295|X4=1420|Y4=295|X5=1410|Y5=295|X6=1410|Y6=310
|RECORD=27|IndexInSheet=176|OwnerPartId=-1|LineWidth=1|Color=8388608|LocationCount=6|X1=1440|Y1=640|X2=1440|Y2=625|X3=1430|Y3=625|X4=1420|Y4=625|X5=1410|Y5=625|X6=1410|Y6=640
|RECORD=27|IndexInSheet=177|OwnerPartId=-1|LineWidth=1|Color=8388608|LocationCount=3|X1=400|Y1=390|X2=310|Y2=390|X3=210|Y3=390
|RECORD=27|IndexInSheet=178|OwnerPartId=-1|LineWidth=1|Color=8388608|LocationCount=3|X1=400|Y1=445|X2=280|Y2=445|X3=210|Y3=445
|RECORD=27|IndexInSheet=179|OwnerPartId=-1|LineWidth=1|Color=8388608|LocationCount=3|X1=400|Y1=720|X2=310|Y2=720|X3=210|Y3=720
|RECORD=27|IndexInSheet=180|OwnerPartId=-1|LineWidth=1|Color=8388608|LocationCount=3|X1=400|Y1=775|X2=280|Y2=775|X3=210|Y3=775
|RECORD=27|IndexInSheet=181|OwnerPartId=-1|LineWidth=1|Color=8388608|LocationCount=2|X1=400|Y1=365|X2=270|Y2=365
|RECORD=27|IndexInSheet=182|OwnerPartId=-1|LineWidth=1|Color=8388608|LocationCount=2|X1=270|Y1=420|X2=400|Y2=420
|RECORD=27|IndexInSheet=183|OwnerPartId=-1|LineWidth=1|Color=8388608|LocationCount=2|X1=400|Y1=695|X2=270|Y2=695
|RECORD=27|IndexInSheet=184|OwnerPartId=-1|LineWidth=1|Color=8388608|LocationCount=2|X1=270|Y1=750|X2=400|Y2=750
|RECORD=27|IndexInSheet=185|OwnerPartId=-1|LineWidth=1|Color=8388608|LocationCount=4|X1=630|Y1=420|X2=600|Y2=420|X3=575|Y3=420|X4=555|Y4=420
|RECORD=27|IndexInSheet=186|OwnerPartId=-1|LineWidth=1|Color=8388608|LocationCount=4|X1=630|Y1=750|X2=600|Y2=750|X3=575|Y3=750|X4=555|Y4=750
|RECORD=27|IndexInSheet=187|OwnerPartId=-1|LineWidth=1|Color=8388608|LocationCount=3|X1=630|Y1=340|X2=600|Y2=340|X3=600|Y3=420
|RECORD=27|IndexInSheet=188|OwnerPartId=-1|LineWidth=1|Color=8388608|LocationCount=3|X1=1160|Y1=390|X2=1070|Y2=390|X3=970|Y3=390
|RECORD=27|IndexInSheet=189|OwnerPartId=-1|LineWidth=1|Color=8388608|LocationCount=3|X1=1160|Y1=445|X2=1040|Y2=445|X3=970|Y3=445
|RECORD=27|IndexInSheet=190|OwnerPartId=-1|LineWidth=1|Color=8388608|LocationCount=3|X1=1160|Y1=720|X2=1070|Y2=720|X3=970|Y3=720
|RECORD=27|IndexInSheet=191|OwnerPartId=-1|LineWidth=1|Color=8388608|LocationCount=3|X1=1160|Y1=775|X2=1040|Y2=775|X3=970|Y3=775
|RECORD=27|IndexInSheet=192|OwnerPartId=-1|LineWidth=1|Color=8388608|LocationCount=2|X1=1160|Y1=365|X2=1030|Y2=365
|RECORD=27|IndexInSheet=193|OwnerPartId=-1|LineWidth=1|Color=8388608|LocationCount=2|X1=1030|Y1=420|X2=1160|Y2=420
|RECORD=27|IndexInSheet=194|OwnerPartId=-1|LineWidth=1|Color=8388608|LocationCount=2|X1=1160|Y1=695|X2=1030|Y2=695
|RECORD=27|IndexInSheet=195|OwnerPartId=-1|LineWidth=1|Color=8388608|LocationCount=2|X1=1030|Y1=750|X2=1160|Y2=750
|RECORD=27|IndexInSheet=196|OwnerPartId=-1|LineWidth=1|Color=8388608|LocationCount=3|X1=1390|Y1=420|X2=1360|Y2=420|X3=1335|Y3=420
|RECORD=27|IndexInSheet=197|OwnerPartId=-1|LineWidth=1|Color=8388608|LocationCount=4|X1=1390|Y1=750|X2=1360|Y2=750|X3=1335|Y3=750|X4=1315|Y4=750
|RECORD=27|IndexInSheet=198|OwnerPartId=-1|LineWidth=1|Color=8388608|LocationCount=3|X1=1390|Y1=340|X2=1360|Y2=340|X3=1360|Y3=420
|RECORD=29|IndexInSheet=-1|OwnerPartId=-1|Location.X=280|Location.Y=445|Color=128
|RECORD=29|IndexInSheet=-1|OwnerPartId=-1|Location.X=280|Location.Y=775|Color=128
|RECORD=29|IndexInSheet=-1|OwnerPartId=-1|Location.X=310|Location.Y=390|Color=128
|RECORD=29|IndexInSheet=-1|OwnerPartId=-1|Location.X=310|Location.Y=720|Color=128
|RECORD=29|IndexInSheet=-1|OwnerPartId=-1|Location.X=340|Location.Y=345|Color=128
|RECORD=29|IndexInSheet=-1|OwnerPartId=-1|Location.X=340|Location.Y=675|Color=128
|RECORD=29|IndexInSheet=-1|OwnerPartId=-1|Location.X=520|Location.Y=420|Color=128
|RECORD=29|IndexInSheet=-1|OwnerPartId=-1|Location.X=520|Location.Y=750|Color=128
|RECORD=29|IndexInSheet=-1|OwnerPartId=-1|Location.X=575|Location.Y=420|Color=128
|RECORD=29|IndexInSheet=-1|OwnerPartId=-1|Location.X=575|Location.Y=750|Color=128
|RECORD=29|IndexInSheet=-1|OwnerPartId=-1|Location.X=600|Location.Y=420|Color=128
|RECORD=29|IndexInSheet=-1|OwnerPartId=-1|Location.X=600|Location.Y=670|Color=128
|RECORD=29|IndexInSheet=-1|OwnerPartId=-1|Location.X=600|Location.Y=750|Color=128
|RECORD=29|IndexInSheet=-1|OwnerPartId=-1|Location.X=660|Location.Y=295|Color=128
|RECORD=29|IndexInSheet=-1|OwnerPartId=-1|Location.X=660|Location.Y=625|Color=128
|RECORD=29|IndexInSheet=-1|OwnerPartId=-1|Location.X=670|Location.Y=295|Color=128
|RECORD=29|IndexInSheet=-1|OwnerPartId=-1|Location.X=670|Location.Y=390|Color=128
|RECORD=29|IndexInSheet=-1|OwnerPartId=-1|Location.X=670|Location.Y=625|Color=128
|RECORD=29|IndexInSheet=-1|OwnerPartId=-1|Location.X=670|Location.Y=720|Color=128
|RECORD=29|IndexInSheet=-1|OwnerPartId=-1|Location.X=680|Location.Y=295|Color=128
|RECORD=29|IndexInSheet=-1|OwnerPartId=-1|Location.X=680|Location.Y=625|Color=128
|RECORD=29|IndexInSheet=-1|OwnerPartId=-1|Location.X=1040|Location.Y=445|Color=128
|RECORD=29|IndexInSheet=-1|OwnerPartId=-1|Location.X=1040|Location.Y=775|Color=128
|RECORD=29|IndexInSheet=-1|OwnerPartId=-1|Location.X=1070|Location.Y=390|Color=128
|RECORD=29|IndexInSheet=-1|OwnerPartId=-1|Location.X=1070|Location.Y=720|Color=128
|RECORD=29|IndexInSheet=-1|OwnerPartId=-1|Location.X=1100|Location.Y=345|Color=128
|RECORD=29|IndexInSheet=-1|OwnerPartId=-1|Location.X=1100|Location.Y=675|Color=128
|RECORD=29|IndexInSheet=-1|OwnerPartId=-1|Location.X=1280|Location.Y=420|Color=128
|RECORD=29|IndexInSheet=-1|OwnerPartId=-1|Location.X=1280|Location.Y=750|Color=128
|RECORD=29|IndexInSheet=-1|OwnerPartId=-1|Location.X=1335|Location.Y=750|Color=128
|RECORD=29|IndexInSheet=-1|OwnerPartId=-1|Location.X=1360|Location.Y=420|Color=128
|RECORD=29|IndexInSheet=-1|OwnerPartId=-1|Location.X=1360|Location.Y=670|Color=128
|RECORD=29|IndexInSheet=-1|OwnerPartId=-1|Location.X=1360|Location.Y=750|Color=128
|RECORD=29|IndexInSheet=-1|OwnerPartId=-1|Location.X=1420|Location.Y=295|Color=128
|RECORD=29|IndexInSheet=-1|OwnerPartId=-1|Location.X=1420|Location.Y=625|Color=128
|RECORD=29|IndexInSheet=-1|OwnerPartId=-1|Location.X=1430|Location.Y=295|Color=128
|RECORD=29|IndexInSheet=-1|OwnerPartId=-1|Location.X=1430|Location.Y=390|Color=128
|RECORD=29|IndexInSheet=-1|OwnerPartId=-1|Location.X=1430|Location.Y=625|Color=128
|RECORD=29|IndexInSheet=-1|OwnerPartId=-1|Location.X=1430|Location.Y=720|Color=128
|RECORD=29|IndexInSheet=-1|OwnerPartId=-1|Location.X=1440|Location.Y=295|Color=128
|RECORD=29|IndexInSheet=-1|OwnerPartId=-1|Location.X=1440|Location.Y=625|Color=128